FILE_TYPE = MACRO_DRAWING;
SET COLOR_WIRE YELLOW;
SET COLOR_PROP ORANGE;
SET COLOR_DOT WHITE;
SET COLOR_ARC YELLOW;
SET COLOR_BODY GREEN;
SET COLOR_NOTE PURPLE;
SET PROP_DISPLAY VALUE;
SET PAGE_NUMBER P371;
FORCEADD METR3904G..1
R 2
(-6100 1950);
FORCEPROP 1 LAST LOCATION Q6001
J 2
(-6200 1925);
DISPLAY 0.723404 (-6200 1925);
PAINT AQUA (-6200 1925);
FORCEPROP 0 LAST $SEC 1
J 2
(-6175 2050);
DISPLAY INVISIBLE (-6175 2050);
FORCEPROP 0 LAST CDS_SEC 1
J 2
(-6175 2050);
DISPLAY INVISIBLE (-6175 2050);
FORCEPROP 0 LASTPIN (-6000 1950) $PN B
J 0
(-5990 1960);
DISPLAY 0.808511 (-5990 1960);
FORCEPROP 0 LASTPIN (-6150 1850) $PN E
R 1
J 2
(-6110 1885);
DISPLAY 0.808511 (-6110 1885);
FORCEPROP 0 LASTPIN (-6150 2050) $PN C
R 1
J 0
(-6110 2060);
DISPLAY 0.808511 (-6110 2060);
FORCEPROP 1 LAST MATERIAL IC
J 2
(-6225 1825);
DISPLAY 0.723404 (-6225 1825);
PAINT SKYBLUE (-6225 1825);
FORCEPROP 0 LAST ROOM HSC BOM2
J 0
(-6475 1775);
DISPLAY 0.680851 (-6475 1775);
FORCEPROP 2 LAST VALUE METR3904-G
J 2
(-6200 1975);
DISPLAY 0.723404 (-6200 1975);
PAINT SKYBLUE (-6200 1975);
FORCEPROP 2 LAST PART_TYPE SMLF
J 2
(-6200 2025);
DISPLAY 1.021277 (-6200 2025);
FORCEPROP 1 LAST NEEDS_NO_SIZE TRUE
J 2
(-6100 1950);
DISPLAY 0.468085 (-6100 1950);
PAINT GREEN (-6100 1950);
DISPLAY INVISIBLE (-6100 1950);
FORCEPROP 2 LAST CDS_LIB pure_quanta
J 2
(-6100 1950);
PAINT MONO (-6100 1950);
DISPLAY INVISIBLE (-6100 1950);
FORCEPROP 1 LAST PATH I1
J 2
(-6250 1805);
DISPLAY 0.723404 (-6250 1805);
PAINT GREEN (-6250 1805);
DISPLAY INVISIBLE (-6250 1805);
FORCEPROP 1 LAST PART_NUMBER BA039040020
J 2
(-6200 1875);
DISPLAY 0.723404 (-6200 1875);
PAINT WHITE (-6200 1875);
DISPLAY INVISIBLE (-6200 1875);
FORCEADD Q_RES..1
(-2500 2025);
FORCEPROP 1 LAST LOCATION R2628
J 0
(-2700 2025);
DISPLAY 0.553191 (-2700 2025);
FORCEPROP 0 LAST $SEC 1
J 0
(-2400 2100);
DISPLAY 0.680851 (-2400 2100);
PAINT MONO (-2400 2100);
DISPLAY INVISIBLE (-2400 2100);
FORCEPROP 0 LAST CDS_SEC 1
J 0
(-2400 2100);
DISPLAY 1.021277 (-2400 2100);
DISPLAY INVISIBLE (-2400 2100);
FORCEPROP 1 LASTPIN (-2600 2025) $PN 1
J 0
(-2588 2037);
DISPLAY 0.808511 (-2588 2037);
PAINT WHITE (-2588 2037);
FORCEPROP 1 LASTPIN (-2400 2025) $PN 2
J 0
(-2438 2037);
DISPLAY 0.808511 (-2438 2037);
PAINT WHITE (-2438 2037);
FORCEPROP 0 LAST ROOM HSC BOM2
J 0
(-2375 2050);
DISPLAY 0.446809 (-2375 2050);
FORCEPROP 1 LAST MATERIAL CHIP
J 0
(-2275 2025);
DISPLAY 0.404255 (-2275 2025);
FORCEPROP 1 LAST VALUE 0
J 2
(-2350 2025);
DISPLAY 0.404255 (-2350 2025);
FORCEPROP 1 LAST TOLERANCE 5%
J 0
(-2325 2025);
DISPLAY 0.404255 (-2325 2025);
FORCEPROP 1 LAST PACK_TYPE 0402LF
J 0
(-2625 2000);
DISPLAY 0.319149 (-2625 2000);
FORCEPROP 1 LAST WATTAGE 1/16W
J 2
(-2375 2000);
DISPLAY 0.319149 (-2375 2000);
FORCEPROP 2 LAST CDS_LIB pure_quanta
J 0
(-2500 2025);
DISPLAY INVISIBLE (-2500 2025);
FORCEPROP 1 LAST PATH I10
J 0
(-2550 2175);
DISPLAY 0.978723 (-2550 2175);
PAINT WHITE (-2550 2175);
DISPLAY INVISIBLE (-2550 2175);
FORCEPROP 1 LAST PART_NUMBER CS00002JB13
J 0
(-2625 1975);
DISPLAY 0.319149 (-2625 1975);
DISPLAY INVISIBLE (-2625 1975);
FORCEADD UNIVERSAL_POWER..1
(-4550 4075);
FORCEPROP 3 LASTPIN (-4550 4025) SIG_NAME P3V3_AUX\g
J 0
(-4540 4035);
DISPLAY 0.659574 (-4540 4035);
PAINT MONO (-4540 4035);
DISPLAY INVISIBLE (-4540 4035);
FORCEPROP 1 LAST HDL_POWER P3V3_AUX
J 1
(-4550 4125);
DISPLAY 0.723404 (-4550 4125);
PAINT GREEN (-4550 4125);
FORCEPROP 2 LAST CDS_LIB pure_quanta_power
J 0
(-4550 4075);
DISPLAY INVISIBLE (-4550 4075);
FORCEPROP 1 LAST PATH I100
J 0
(-4500 4100);
DISPLAY 0.872340 (-4500 4100);
PAINT AQUA (-4500 4100);
DISPLAY INVISIBLE (-4500 4100);
FORCEADD LM4040AIM3X25NOPB..1
(-8525 2875);
FORCEPROP 1 LAST LOCATION U8005
J 0
(-8725 3200);
DISPLAY 0.574468 (-8725 3200);
PAINT GREEN (-8725 3200);
FORCEPROP 0 LAST $SEC 1
J 0
(-8725 3400);
DISPLAY 0.680851 (-8725 3400);
PAINT MONO (-8725 3400);
DISPLAY INVISIBLE (-8725 3400);
FORCEPROP 0 LAST CDS_SEC 1
J 0
(-8725 3400);
DISPLAY 1.021277 (-8725 3400);
DISPLAY INVISIBLE (-8725 3400);
FORCEPROP 0 LASTPIN (-8875 3025) $PN 1
J 2
(-8885 3035);
DISPLAY 0.680851 (-8885 3035);
PAINT MONO (-8885 3035);
FORCEPROP 0 LASTPIN (-8875 2725) $PN 2
J 2
(-8885 2735);
DISPLAY 0.680851 (-8885 2735);
PAINT MONO (-8885 2735);
FORCEPROP 0 LASTPIN (-8175 2875) $PN 3
J 0
(-8165 2885);
DISPLAY 0.680851 (-8165 2885);
PAINT MONO (-8165 2885);
FORCEPROP 0 LAST ROOM HSC BOM2
J 0
(-8725 3350);
DISPLAY 0.680851 (-8725 3350);
FORCEPROP 2 LAST PART_TYPE SMLF
J 0
(-8725 3300);
DISPLAY 0.808511 (-8725 3300);
FORCEPROP 1 LAST MATERIAL EMPTY
J 0
(-8728 3130);
DISPLAY 0.723404 (-8728 3130);
PAINT RED (-8728 3130);
FORCEPROP 2 LAST VALUE LM4040AIM3X-2.5/NOPB
J 0
(-8725 3250);
DISPLAY 0.638298 (-8725 3250);
FORCEPROP 2 LAST CDS_LIB pure_quanta
J 0
(-8525 2875);
DISPLAY INVISIBLE (-8525 2875);
FORCEPROP 1 LAST PIN_NAMES_ROTATE True
J 0
(-8525 2875);
DISPLAY 0.489362 (-8525 2875);
PAINT GREEN (-8525 2875);
DISPLAY INVISIBLE (-8525 2875);
FORCEPROP 1 LAST CDS_LMAN_SYM_OUTLINE -200,250,200,-250
J 0
(-8525 2875);
DISPLAY 0.468085 (-8525 2875);
PAINT GREEN (-8525 2875);
DISPLAY INVISIBLE (-8525 2875);
FORCEPROP 1 LAST PATH I101
J 0
(-8525 2875);
DISPLAY 0.723404 (-8525 2875);
PAINT GREEN (-8525 2875);
DISPLAY INVISIBLE (-8525 2875);
FORCEPROP 1 LAST PART_NUMBER AL404025013
J 0
(-8725 3175);
DISPLAY 0.723404 (-8725 3175);
PAINT GREEN (-8725 3175);
DISPLAY INVISIBLE (-8725 3175);
FORCEADD OFFPAGE..4
R 2
(-8375 3950);
FORCEPROP 2 LAST $XR0 268 
J 0
(-8627 3950);
DISPLAY 0.638298 (-8627 3950);
PAINT MONO (-8627 3950);
FORCEPROP 2 LAST CDS_LIB standard
J 0
(-8375 3950);
DISPLAY INVISIBLE (-8375 3950);
FORCEPROP 1 LAST OFFPAGE TRUE
J 2
(-8700 3825);
DISPLAY 0.872340 (-8700 3825);
PAINT GREEN (-8700 3825);
DISPLAY INVISIBLE (-8700 3825);
FORCEPROP 1 LAST COMMENT_BODY TRUE
J 2
(-8350 3850);
DISPLAY 0.872340 (-8350 3850);
PAINT GREEN (-8350 3850);
DISPLAY INVISIBLE (-8350 3850);
FORCEPROP 2 LAST PATH I102
J 0
(-8650 4000);
DISPLAY 0.680851 (-8650 4000);
DISPLAY INVISIBLE (-8650 4000);
FORCEADD Q_RES..1
(-6300 3800);
FORCEPROP 1 LAST LOCATION R8112
J 0
(-6425 3725);
DISPLAY 1.021277 (-6425 3725);
FORCEPROP 0 LAST $SEC 1
J 0
(-6425 3900);
DISPLAY 0.680851 (-6425 3900);
PAINT MONO (-6425 3900);
DISPLAY INVISIBLE (-6425 3900);
FORCEPROP 0 LAST CDS_SEC 1
J 0
(-6425 3900);
DISPLAY 1.021277 (-6425 3900);
DISPLAY INVISIBLE (-6425 3900);
FORCEPROP 1 LASTPIN (-6400 3800) $PN 1
J 0
(-6388 3812);
DISPLAY 0.787234 (-6388 3812);
PAINT MONO (-6388 3812);
FORCEPROP 1 LASTPIN (-6200 3800) $PN 2
J 0
(-6238 3812);
DISPLAY 0.787234 (-6238 3812);
PAINT MONO (-6238 3812);
FORCEPROP 1 LAST TOLERANCE 1%
J 0
(-6025 3800);
DISPLAY 0.638298 (-6025 3800);
FORCEPROP 0 LAST ROOM HSC BOM2
J 0
(-6175 3725);
DISPLAY 0.680851 (-6175 3725);
FORCEPROP 1 LAST VALUE 1M
J 2
(-5875 3800);
DISPLAY 0.638298 (-5875 3800);
FORCEPROP 1 LAST PACK_TYPE 0402LF
J 0
(-5675 3800);
DISPLAY 0.638298 (-5675 3800);
FORCEPROP 1 LAST MATERIAL EMPTY
J 0
(-6175 3800);
DISPLAY 0.638298 (-6175 3800);
FORCEPROP 1 LAST WATTAGE 1/16W
J 2
(-5700 3800);
DISPLAY 0.638298 (-5700 3800);
FORCEPROP 2 LAST CDS_LIB pure_quanta
J 0
(-6300 3800);
DISPLAY INVISIBLE (-6300 3800);
FORCEPROP 1 LAST PATH I103
J 0
(-6350 3950);
DISPLAY 0.978723 (-6350 3950);
PAINT WHITE (-6350 3950);
DISPLAY INVISIBLE (-6350 3950);
FORCEPROP 1 LAST PART_NUMBER CS51002FB05
J 0
(-6425 3850);
DISPLAY 0.638298 (-6425 3850);
DISPLAY INVISIBLE (-6425 3850);
FORCEADD AP331AWG7..1
(-6750 3475);
FORCEPROP 1 LAST LOCATION U8006
J 0
(-6644 3331);
DISPLAY 0.723404 (-6644 3331);
PAINT GREEN (-6644 3331);
FORCEPROP 0 LAST $SEC 1
J 0
(-6625 3475);
DISPLAY 0.680851 (-6625 3475);
PAINT MONO (-6625 3475);
DISPLAY INVISIBLE (-6625 3475);
FORCEPROP 0 LAST CDS_SEC 1
J 0
(-6625 3475);
DISPLAY 1.021277 (-6625 3475);
DISPLAY INVISIBLE (-6625 3475);
FORCEPROP 0 LASTPIN (-6750 3225) $PN 2
R 1
J 2
(-6760 3215);
DISPLAY 0.680851 (-6760 3215);
PAINT MONO (-6760 3215);
FORCEPROP 0 LASTPIN (-7000 3525) $PN 3
J 2
(-7010 3535);
DISPLAY 0.680851 (-7010 3535);
PAINT MONO (-7010 3535);
FORCEPROP 0 LASTPIN (-7000 3425) $PN 1
J 2
(-7010 3435);
DISPLAY 0.680851 (-7010 3435);
PAINT MONO (-7010 3435);
FORCEPROP 0 LASTPIN (-6500 3475) $PN 4
J 0
(-6490 3485);
DISPLAY 0.680851 (-6490 3485);
PAINT MONO (-6490 3485);
FORCEPROP 0 LASTPIN (-6750 3725) $PN 5
R 1
J 0
(-6760 3735);
DISPLAY 0.680851 (-6760 3735);
PAINT MONO (-6760 3735);
FORCEPROP 2 LAST PART_TYPE SMLF
J 0
(-6625 3425);
DISPLAY 1.021277 (-6625 3425);
FORCEPROP 1 LAST MATERIAL EMPTY
J 0
(-6650 3225);
DISPLAY 0.723404 (-6650 3225);
PAINT RED (-6650 3225);
FORCEPROP 2 LAST VALUE AP331AWG-7
J 0
(-6625 3375);
DISPLAY 1.021277 (-6625 3375);
FORCEPROP 0 LAST ROOM HSC BOM2
J 0
(-6650 3175);
DISPLAY 0.680851 (-6650 3175);
FORCEPROP 2 LAST CDS_LIB pure_quanta
J 0
(-6750 3475);
DISPLAY INVISIBLE (-6750 3475);
FORCEPROP 1 LAST NEEDS_NO_SIZE TRUE
J 0
(-6750 3475);
DISPLAY 0.723404 (-6750 3475);
PAINT GREEN (-6750 3475);
DISPLAY INVISIBLE (-6750 3475);
FORCEPROP 1 LAST CDS_LMAN_SYM_OUTLINE -100,100,100,-100
J 0
(-6750 3475);
DISPLAY 0.468085 (-6750 3475);
PAINT GREEN (-6750 3475);
DISPLAY INVISIBLE (-6750 3475);
FORCEPROP 1 LAST PATH I104
J 0
(-6750 3475);
DISPLAY 0.723404 (-6750 3475);
PAINT GREEN (-6750 3475);
DISPLAY INVISIBLE (-6750 3475);
FORCEPROP 1 LAST PART_NUMBER AL000331011
J 0
(-6644 3284);
DISPLAY 0.723404 (-6644 3284);
PAINT GREEN (-6644 3284);
DISPLAY INVISIBLE (-6644 3284);
FORCEADD OFFPAGE..4
R 2
(-3875 6275);
FORCEPROP 2 LAST $XR0 268 
J 0
(-4127 6275);
DISPLAY 0.638298 (-4127 6275);
PAINT MONO (-4127 6275);
FORCEPROP 2 LAST CDS_LIB standard
J 0
(-3875 6275);
DISPLAY INVISIBLE (-3875 6275);
FORCEPROP 1 LAST OFFPAGE TRUE
J 2
(-4200 6150);
DISPLAY 0.872340 (-4200 6150);
PAINT GREEN (-4200 6150);
DISPLAY INVISIBLE (-4200 6150);
FORCEPROP 1 LAST COMMENT_BODY TRUE
J 2
(-3850 6175);
DISPLAY 0.872340 (-3850 6175);
PAINT GREEN (-3850 6175);
DISPLAY INVISIBLE (-3850 6175);
FORCEPROP 2 LAST PATH I105
J 0
(-3825 6350);
DISPLAY 0.680851 (-3825 6350);
DISPLAY INVISIBLE (-3825 6350);
FORCEADD GND..1
(-6825 5975);
FORCEPROP 3 LASTPIN (-6825 6025) SIG_NAME GND\g
J 0
(-6815 6035);
DISPLAY 0.659574 (-6815 6035);
PAINT MONO (-6815 6035);
DISPLAY INVISIBLE (-6815 6035);
FORCEPROP 1 LAST SIZE 1B
J 0
(-6750 5925);
DISPLAY 0.872340 (-6750 5925);
PAINT AQUA (-6750 5925);
DISPLAY INVISIBLE (-6750 5925);
FORCEPROP 2 LAST ROOM VR_DDR1_POWER_STAGE
J 0
(-7050 6050);
DISPLAY INVISIBLE (-7050 6050);
FORCEPROP 2 LAST CDS_LIB pure_quanta_power
J 0
(-6825 5975);
DISPLAY INVISIBLE (-6825 5975);
FORCEPROP 1 LAST HDL_POWER GND
J 0
(-6825 6125);
DISPLAY 1.170213 (-6825 6125);
PAINT GREEN (-6825 6125);
DISPLAY INVISIBLE (-6825 6125);
FORCEPROP 1 LAST PATH I106
J 0
(-6750 5975);
DISPLAY 0.872340 (-6750 5975);
PAINT AQUA (-6750 5975);
DISPLAY INVISIBLE (-6750 5975);
FORCEADD Q_CAP..1
(-6825 6275);
FORCEPROP 1 LAST LOCATION C6084
J 0
(-6775 6375);
DISPLAY 0.638298 (-6775 6375);
FORCEPROP 0 LAST $SEC 1
J 0
(-6775 6425);
DISPLAY 0.680851 (-6775 6425);
PAINT MONO (-6775 6425);
DISPLAY INVISIBLE (-6775 6425);
FORCEPROP 0 LAST CDS_SEC 1
J 0
(-6775 6425);
DISPLAY 0.680851 (-6775 6425);
DISPLAY INVISIBLE (-6775 6425);
FORCEPROP 1 LASTPIN (-6825 6375) $PN 1
J 0
(-6815 6355);
DISPLAY 0.787234 (-6815 6355);
PAINT MONO (-6815 6355);
FORCEPROP 1 LASTPIN (-6825 6175) $PN 2
J 0
(-6815 6155);
DISPLAY 0.787234 (-6815 6155);
PAINT MONO (-6815 6155);
FORCEPROP 1 LAST VOLTAGE 25V
J 0
(-6775 6275);
DISPLAY 0.638298 (-6775 6275);
FORCEPROP 1 LAST TOLERANCE 10%
J 0
(-6775 6225);
DISPLAY 0.638298 (-6775 6225);
FORCEPROP 1 LAST PACK_TYPE 0402
J 0
(-6775 6075);
DISPLAY 0.638298 (-6775 6075);
FORCEPROP 1 LAST VALUE 0.1UF
J 0
(-6775 6325);
DISPLAY 0.638298 (-6775 6325);
FORCEPROP 1 LAST MATERIAL EMPTY
J 0
(-6775 6175);
DISPLAY 0.638298 (-6775 6175);
FORCEPROP 0 LAST ROOM HSC BOM2
J 0
(-6775 6000);
DISPLAY 0.680851 (-6775 6000);
FORCEPROP 2 LAST CDS_LIB pure_quanta
J 0
(-6825 6275);
DISPLAY INVISIBLE (-6825 6275);
FORCEPROP 1 LAST PATH I107
J 0
(-6775 6425);
DISPLAY 0.978723 (-6775 6425);
PAINT WHITE (-6775 6425);
DISPLAY INVISIBLE (-6775 6425);
FORCEPROP 1 LAST PART_NUMBER CH4104K1B00
J 0
(-6775 6125);
DISPLAY 0.638298 (-6775 6125);
DISPLAY INVISIBLE (-6775 6125);
FORCEADD Q_RES..2
(-6375 6625);
FORCEPROP 1 LAST LOCATION R9020
J 0
(-6330 6750);
DISPLAY 0.723404 (-6330 6750);
PAINT AQUA (-6330 6750);
FORCEPROP 0 LAST $SEC 1
J 0
(-6325 6800);
DISPLAY 0.680851 (-6325 6800);
PAINT MONO (-6325 6800);
DISPLAY INVISIBLE (-6325 6800);
FORCEPROP 0 LAST CDS_SEC 1
J 0
(-6325 6800);
DISPLAY 0.680851 (-6325 6800);
DISPLAY INVISIBLE (-6325 6800);
FORCEPROP 1 LASTPIN (-6375 6725) $PN 1
J 0
(-6370 6687);
DISPLAY 0.787234 (-6370 6687);
PAINT MONO (-6370 6687);
FORCEPROP 1 LASTPIN (-6375 6525) $PN 2
J 0
(-6370 6535);
DISPLAY 0.787234 (-6370 6535);
PAINT MONO (-6370 6535);
FORCEPROP 1 LAST PACK_TYPE 0402LF
J 0
(-6325 6500);
DISPLAY 0.723404 (-6325 6500);
PAINT SKYBLUE (-6325 6500);
FORCEPROP 1 LAST MATERIAL EMPTY
J 0
(-6335 6550);
DISPLAY 0.723404 (-6335 6550);
PAINT RED (-6335 6550);
FORCEPROP 1 LAST WATTAGE 1/16W
J 0
(-6335 6600);
DISPLAY 0.723404 (-6335 6600);
PAINT SKYBLUE (-6335 6600);
FORCEPROP 1 LAST TOLERANCE 1%
J 0
(-6330 6650);
DISPLAY 0.723404 (-6330 6650);
PAINT SKYBLUE (-6330 6650);
FORCEPROP 1 LAST VALUE 1K
J 0
(-6330 6700);
DISPLAY 0.723404 (-6330 6700);
PAINT SKYBLUE (-6330 6700);
FORCEPROP 0 LAST ROOM HSC BOM2
J 0
(-6325 6800);
DISPLAY 0.680851 (-6325 6800);
FORCEPROP 2 LAST CDS_LIB pure_quanta
J 0
(-6375 6625);
DISPLAY INVISIBLE (-6375 6625);
FORCEPROP 1 LAST PATH I108
J 0
(-6325 6800);
DISPLAY 0.978723 (-6325 6800);
PAINT WHITE (-6325 6800);
DISPLAY INVISIBLE (-6325 6800);
FORCEPROP 1 LAST PART_NUMBER CS21002FB06
J 0
(-6335 6500);
DISPLAY 0.723404 (-6335 6500);
PAINT WHITE (-6335 6500);
DISPLAY INVISIBLE (-6335 6500);
FORCEADD UNIVERSAL_POWER..1
(-6375 6825);
FORCEPROP 3 LASTPIN (-6375 6775) SIG_NAME P3V3_AUX\g
J 0
(-6365 6785);
DISPLAY 0.659574 (-6365 6785);
PAINT MONO (-6365 6785);
DISPLAY INVISIBLE (-6365 6785);
FORCEPROP 1 LAST HDL_POWER P3V3_AUX
J 1
(-6375 6875);
DISPLAY 0.723404 (-6375 6875);
PAINT GREEN (-6375 6875);
FORCEPROP 2 LAST CDS_LIB pure_quanta_power
J 0
(-6375 6825);
DISPLAY INVISIBLE (-6375 6825);
FORCEPROP 1 LAST PATH I109
J 0
(-6325 6850);
DISPLAY 0.872340 (-6325 6850);
PAINT AQUA (-6325 6850);
DISPLAY INVISIBLE (-6325 6850);
FORCEADD OFFPAGE..5
R 2
(-1475 2025);
FORCEPROP 2 LAST $XR0 82 
J 0
(-1286 2025);
DISPLAY 0.638298 (-1286 2025);
PAINT MONO (-1286 2025);
FORCEPROP 2 LAST CDS_LIB standard
J 2
(-1475 2025);
DISPLAY INVISIBLE (-1475 2025);
FORCEPROP 1 LAST OFFPAGE TRUE
J 2
(-1800 1900);
DISPLAY 0.872340 (-1800 1900);
PAINT GREEN (-1800 1900);
DISPLAY INVISIBLE (-1800 1900);
FORCEPROP 1 LAST COMMENT_BODY TRUE
J 2
(-1575 1950);
DISPLAY 0.872340 (-1575 1950);
PAINT PEACH (-1575 1950);
DISPLAY INVISIBLE (-1575 1950);
FORCEPROP 2 LAST PATH I11
J 0
(-1300 2100);
DISPLAY 0.680851 (-1300 2100);
DISPLAY INVISIBLE (-1300 2100);
FORCEADD Q_CAP..1
R 2
(-6375 6250);
FORCEPROP 1 LAST LOCATION C9003
J 0
(-6300 6400);
DISPLAY 0.617021 (-6300 6400);
PAINT AQUA (-6300 6400);
FORCEPROP 0 LAST $SEC 1
J 0
(-6300 6450);
DISPLAY 0.680851 (-6300 6450);
PAINT MONO (-6300 6450);
DISPLAY INVISIBLE (-6300 6450);
FORCEPROP 0 LAST CDS_SEC 1
J 0
(-6300 6450);
DISPLAY 0.680851 (-6300 6450);
DISPLAY INVISIBLE (-6300 6450);
FORCEPROP 1 LASTPIN (-6375 6350) $PN 1
J 2
(-6385 6330);
DISPLAY 0.787234 (-6385 6330);
PAINT MONO (-6385 6330);
FORCEPROP 1 LASTPIN (-6375 6150) $PN 2
J 2
(-6385 6130);
DISPLAY 0.787234 (-6385 6130);
PAINT MONO (-6385 6130);
FORCEPROP 0 LAST ROOM HSC BOM2
J 0
(-6325 6025);
DISPLAY 0.680851 (-6325 6025);
FORCEPROP 1 LAST PACK_TYPE C0402
J 0
(-6300 6075);
DISPLAY 0.617021 (-6300 6075);
PAINT SKYBLUE (-6300 6075);
FORCEPROP 1 LAST MATERIAL EMPTY
J 0
(-6300 6175);
DISPLAY 0.617021 (-6300 6175);
PAINT RED (-6300 6175);
FORCEPROP 1 LAST TOLERANCE 10%
J 0
(-6300 6225);
DISPLAY 0.617021 (-6300 6225);
PAINT SKYBLUE (-6300 6225);
FORCEPROP 1 LAST VALUE 1UF
J 0
(-6300 6325);
DISPLAY 0.617021 (-6300 6325);
PAINT SKYBLUE (-6300 6325);
FORCEPROP 1 LAST VOLTAGE 25V
J 0
(-6300 6275);
DISPLAY 0.617021 (-6300 6275);
PAINT SKYBLUE (-6300 6275);
FORCEPROP 2 LAST CDS_LIB pure_quanta
J 2
(-6375 6250);
DISPLAY INVISIBLE (-6375 6250);
FORCEPROP 1 LAST PATH I110
J 2
(-6425 6400);
DISPLAY 0.978723 (-6425 6400);
PAINT WHITE (-6425 6400);
DISPLAY INVISIBLE (-6425 6400);
FORCEPROP 1 LAST PART_NUMBER CH5104KEB02
J 0
(-6300 6125);
DISPLAY 0.617021 (-6300 6125);
PAINT SKYBLUE (-6300 6125);
DISPLAY INVISIBLE (-6300 6125);
FORCEADD UNIVERSAL_POWER..1
(-2700 4825);
FORCEPROP 3 LASTPIN (-2700 4775) SIG_NAME P3V3_AUX\g
J 0
(-2690 4785);
DISPLAY 0.659574 (-2690 4785);
PAINT MONO (-2690 4785);
DISPLAY INVISIBLE (-2690 4785);
FORCEPROP 1 LAST HDL_POWER P3V3_AUX
J 1
(-2700 4875);
DISPLAY 0.872340 (-2700 4875);
PAINT GREEN (-2700 4875);
FORCEPROP 2 LAST CDS_LIB pure_quanta_power
J 0
(-2700 4825);
DISPLAY INVISIBLE (-2700 4825);
FORCEPROP 1 LAST PATH I112
J 0
(-2650 4850);
DISPLAY 0.872340 (-2650 4850);
PAINT AQUA (-2650 4850);
DISPLAY INVISIBLE (-2650 4850);
FORCEADD Q_RES..2
R 2
(-2700 4625);
FORCEPROP 1 LAST LOCATION R9024
J 2
(-2755 4750);
DISPLAY 0.787234 (-2755 4750);
FORCEPROP 2 LAST SEC 1
J 0
(-2750 4850);
DISPLAY 0.680851 (-2750 4850);
PAINT MONO (-2750 4850);
DISPLAY INVISIBLE (-2750 4850);
FORCEPROP 1 LASTPIN (-2700 4725) $PN 1
J 2
(-2705 4687);
DISPLAY 0.787234 (-2705 4687);
PAINT MONO (-2705 4687);
FORCEPROP 1 LASTPIN (-2700 4525) $PN 2
J 2
(-2705 4535);
DISPLAY 0.787234 (-2705 4535);
PAINT MONO (-2705 4535);
FORCEPROP 1 LAST WATTAGE 1/16W
J 2
(-2750 4600);
DISPLAY 0.787234 (-2750 4600);
FORCEPROP 0 LAST ROOM HSC BOM2
J 0
(-3000 4400);
DISPLAY 0.680851 (-3000 4400);
FORCEPROP 1 LAST TOLERANCE 1%
J 2
(-2755 4650);
DISPLAY 0.787234 (-2755 4650);
FORCEPROP 1 LAST MATERIAL CHIP
J 2
(-2750 4550);
DISPLAY 0.787234 (-2750 4550);
FORCEPROP 1 LAST PACK_TYPE 0402LF
J 2
(-2750 4450);
DISPLAY 0.787234 (-2750 4450);
FORCEPROP 1 LAST VALUE 54.9K
J 2
(-2755 4700);
DISPLAY 0.787234 (-2755 4700);
FORCEPROP 2 LAST CDS_LIB pure_quanta
J 2
(-2700 4625);
DISPLAY INVISIBLE (-2700 4625);
FORCEPROP 2 LAST SEC_TYPE 0402LF
J 0
(-2750 4850);
DISPLAY 0.680851 (-2750 4850);
DISPLAY INVISIBLE (-2750 4850);
FORCEPROP 1 LAST PATH I113
J 2
(-2750 4800);
DISPLAY 0.978723 (-2750 4800);
PAINT WHITE (-2750 4800);
DISPLAY INVISIBLE (-2750 4800);
FORCEPROP 1 LAST PART_NUMBER CS35492FB03
J 2
(-2750 4500);
DISPLAY 0.787234 (-2750 4500);
DISPLAY INVISIBLE (-2750 4500);
FORCEADD OFFPAGE..6
R 2
(-1500 2125);
FORCEPROP 2 LAST $XR1 268 
J 0
(-1166 2125);
DISPLAY 0.638298 (-1166 2125);
PAINT MONO (-1166 2125);
FORCEPROP 2 LAST $XR0 253 
J 0
(-1286 2125);
DISPLAY 0.638298 (-1286 2125);
PAINT MONO (-1286 2125);
FORCEPROP 2 LAST CDS_LIB standard
J 2
(-1500 2125);
DISPLAY INVISIBLE (-1500 2125);
FORCEPROP 1 LAST OFFPAGE TRUE
J 2
(-1825 2000);
DISPLAY 0.872340 (-1825 2000);
PAINT GREEN (-1825 2000);
DISPLAY INVISIBLE (-1825 2000);
FORCEPROP 1 LAST COMMENT_BODY TRUE
J 2
(-1600 2050);
DISPLAY 0.872340 (-1600 2050);
PAINT PEACH (-1600 2050);
DISPLAY INVISIBLE (-1600 2050);
FORCEPROP 2 LAST PATH I12
J 0
(-1300 2200);
DISPLAY 0.680851 (-1300 2200);
DISPLAY INVISIBLE (-1300 2200);
FORCEADD OFFPAGE..1
R 2
(-1475 2225);
FORCEPROP 2 LAST $XR1 268 
J 0
(-1169 2225);
DISPLAY 0.638298 (-1169 2225);
PAINT MONO (-1169 2225);
FORCEPROP 2 LAST $XR0 253 
J 0
(-1289 2225);
DISPLAY 0.638298 (-1289 2225);
PAINT MONO (-1289 2225);
FORCEPROP 2 LAST CDS_LIB standard
J 2
(-1475 2225);
DISPLAY INVISIBLE (-1475 2225);
FORCEPROP 1 LAST OFFPAGE TRUE
J 2
(-1800 2100);
DISPLAY 0.872340 (-1800 2100);
PAINT GREEN (-1800 2100);
DISPLAY INVISIBLE (-1800 2100);
FORCEPROP 1 LAST COMMENT_BODY TRUE
J 2
(-1600 2125);
DISPLAY 0.872340 (-1600 2125);
PAINT PEACH (-1600 2125);
DISPLAY INVISIBLE (-1600 2125);
FORCEPROP 2 LAST PATH I13
J 0
(-1300 2300);
DISPLAY 0.680851 (-1300 2300);
DISPLAY INVISIBLE (-1300 2300);
FORCEADD OFFPAGE..3
R 2
(-3075 4000);
FORCEPROP 2 LAST $XR0 151 
J 0
(-3355 4000);
DISPLAY 0.638298 (-3355 4000);
PAINT MONO (-3355 4000);
FORCEPROP 2 LAST $XR1 269 
J 0
(-3475 4000);
DISPLAY 0.638298 (-3475 4000);
PAINT MONO (-3475 4000);
FORCEPROP 2 LAST CDS_LIB standard
J 2
(-3075 4000);
DISPLAY INVISIBLE (-3075 4000);
FORCEPROP 1 LAST OFFPAGE TRUE
J 2
(-3400 3875);
DISPLAY 0.872340 (-3400 3875);
PAINT GREEN (-3400 3875);
DISPLAY INVISIBLE (-3400 3875);
FORCEPROP 1 LAST COMMENT_BODY TRUE
J 2
(-3025 3900);
DISPLAY 0.872340 (-3025 3900);
PAINT GREEN (-3025 3900);
DISPLAY INVISIBLE (-3025 3900);
FORCEPROP 2 LAST PATH I15
J 0
(-3025 4075);
DISPLAY 0.680851 (-3025 4075);
DISPLAY INVISIBLE (-3025 4075);
FORCEADD OFFPAGE..5
(-2925 3950);
FORCEPROP 2 LAST $XR0 263 
J 0
(-3360 3950);
DISPLAY 0.638298 (-3360 3950);
PAINT MONO (-3360 3950);
FORCEPROP 2 LAST $XR1 80 
J 0
(-3450 3950);
DISPLAY 0.638298 (-3450 3950);
PAINT MONO (-3450 3950);
FORCEPROP 2 LAST CDS_LIB standard
J 2
(-2925 3950);
DISPLAY INVISIBLE (-2925 3950);
FORCEPROP 1 LAST OFFPAGE TRUE
J 0
(-2600 3825);
DISPLAY 0.872340 (-2600 3825);
PAINT AQUA (-2600 3825);
DISPLAY INVISIBLE (-2600 3825);
FORCEPROP 1 LAST COMMENT_BODY TRUE
J 0
(-2825 3875);
DISPLAY 1.170213 (-2825 3875);
PAINT GREEN (-2825 3875);
DISPLAY INVISIBLE (-2825 3875);
FORCEPROP 2 LAST PATH I16
J 0
(-2875 4025);
DISPLAY 0.680851 (-2875 4025);
DISPLAY INVISIBLE (-2875 4025);
FORCEADD OFFPAGE..4
R 2
(-3075 4050);
FORCEPROP 2 LAST $XR0 151 
J 0
(-3327 4050);
DISPLAY 0.638298 (-3327 4050);
PAINT MONO (-3327 4050);
FORCEPROP 2 LAST $XR1 269 
J 0
(-3447 4050);
DISPLAY 0.638298 (-3447 4050);
PAINT MONO (-3447 4050);
FORCEPROP 2 LAST CDS_LIB standard
J 0
(-3075 4050);
DISPLAY INVISIBLE (-3075 4050);
FORCEPROP 1 LAST OFFPAGE TRUE
J 2
(-3400 3925);
DISPLAY 0.872340 (-3400 3925);
PAINT GREEN (-3400 3925);
DISPLAY INVISIBLE (-3400 3925);
FORCEPROP 1 LAST COMMENT_BODY TRUE
J 2
(-3050 3950);
DISPLAY 0.872340 (-3050 3950);
PAINT GREEN (-3050 3950);
DISPLAY INVISIBLE (-3050 3950);
FORCEPROP 2 LAST PATH I17
J 0
(-3025 4125);
DISPLAY 0.680851 (-3025 4125);
DISPLAY INVISIBLE (-3025 4125);
FORCEADD OFFPAGE..5
(-2925 4100);
FORCEPROP 2 LAST $XR0 272 
J 0
(-3210 4100);
DISPLAY 0.638298 (-3210 4100);
PAINT MONO (-3210 4100);
FORCEPROP 2 LAST CDS_LIB standard
J 0
(-2925 4100);
DISPLAY INVISIBLE (-2925 4100);
FORCEPROP 1 LAST OFFPAGE TRUE
J 0
(-2600 3975);
DISPLAY 0.872340 (-2600 3975);
PAINT AQUA (-2600 3975);
DISPLAY INVISIBLE (-2600 3975);
FORCEPROP 1 LAST COMMENT_BODY TRUE
J 0
(-2825 4025);
DISPLAY 1.170213 (-2825 4025);
PAINT GREEN (-2825 4025);
DISPLAY INVISIBLE (-2825 4025);
FORCEPROP 2 LAST PATH I18
J 0
(-2875 4175);
DISPLAY 0.680851 (-2875 4175);
DISPLAY INVISIBLE (-2875 4175);
FORCEADD Q_RES..1
(-5300 1775);
FORCEPROP 1 LAST LOCATION R2624
J 0
(-5450 1825);
DISPLAY 0.638298 (-5450 1825);
FORCEPROP 0 LAST $SEC 1
J 0
(-5125 1850);
DISPLAY 0.680851 (-5125 1850);
PAINT MONO (-5125 1850);
DISPLAY INVISIBLE (-5125 1850);
FORCEPROP 0 LAST CDS_SEC 1
J 0
(-5250 1950);
DISPLAY 1.021277 (-5250 1950);
DISPLAY INVISIBLE (-5250 1950);
FORCEPROP 1 LASTPIN (-5400 1775) $PN 1
J 0
(-5388 1787);
DISPLAY 0.787234 (-5388 1787);
PAINT MONO (-5388 1787);
FORCEPROP 1 LASTPIN (-5200 1775) $PN 2
J 0
(-5238 1787);
DISPLAY 0.787234 (-5238 1787);
PAINT MONO (-5238 1787);
FORCEPROP 1 LAST TOLERANCE 1%
J 0
(-5225 1725);
DISPLAY 0.638298 (-5225 1725);
FORCEPROP 1 LAST VALUE 49.9
J 2
(-5050 1800);
DISPLAY 0.638298 (-5050 1800);
FORCEPROP 0 LAST ROOM HSC BOM2
J 0
(-5300 1850);
DISPLAY 0.553191 (-5300 1850);
FORCEPROP 1 LAST MATERIAL CHIP
J 0
(-5225 1675);
DISPLAY 0.638298 (-5225 1675);
FORCEPROP 1 LAST PACK_TYPE 0402LF
J 0
(-5475 1675);
DISPLAY 0.638298 (-5475 1675);
FORCEPROP 1 LAST WATTAGE 1/16W
J 2
(-5325 1725);
DISPLAY 0.638298 (-5325 1725);
FORCEPROP 2 LAST CDS_LIB pure_quanta
J 0
(-5300 1775);
DISPLAY INVISIBLE (-5300 1775);
FORCEPROP 1 LAST PATH I2
J 0
(-5350 1925);
DISPLAY 0.978723 (-5350 1925);
PAINT WHITE (-5350 1925);
DISPLAY INVISIBLE (-5350 1925);
FORCEPROP 1 LAST PART_NUMBER CS04992FB07
J 0
(-5475 1625);
DISPLAY 0.638298 (-5475 1625);
DISPLAY INVISIBLE (-5475 1625);
FORCEADD OFFPAGE..5
(-2925 4200);
FORCEPROP 2 LAST $XR3 254 
J 0
(-3570 4200);
DISPLAY 0.638298 (-3570 4200);
PAINT MONO (-3570 4200);
FORCEPROP 2 LAST $XR1 189 
J 0
(-3330 4200);
DISPLAY 0.638298 (-3330 4200);
PAINT MONO (-3330 4200);
FORCEPROP 2 LAST $XR0 263 
J 0
(-3210 4200);
DISPLAY 0.638298 (-3210 4200);
PAINT MONO (-3210 4200);
FORCEPROP 2 LAST $XR2 243 
J 0
(-3450 4200);
DISPLAY 0.638298 (-3450 4200);
PAINT MONO (-3450 4200);
FORCEPROP 2 LAST CDS_LIB standard
J 0
(-2925 4200);
DISPLAY INVISIBLE (-2925 4200);
FORCEPROP 1 LAST OFFPAGE TRUE
J 0
(-2600 4075);
DISPLAY 0.872340 (-2600 4075);
PAINT AQUA (-2600 4075);
DISPLAY INVISIBLE (-2600 4075);
FORCEPROP 1 LAST COMMENT_BODY TRUE
J 0
(-2825 4125);
DISPLAY 1.170213 (-2825 4125);
PAINT GREEN (-2825 4125);
DISPLAY INVISIBLE (-2825 4125);
FORCEPROP 2 LAST PATH I20
J 0
(-2875 4275);
DISPLAY 0.680851 (-2875 4275);
DISPLAY INVISIBLE (-2875 4275);
FORCEADD OFFPAGE..4
R 2
(-2925 4250);
FORCEPROP 2 LAST $XR0 269 
J 0
(-3207 4250);
DISPLAY 0.638298 (-3207 4250);
PAINT MONO (-3207 4250);
FORCEPROP 2 LAST $XR1 263 
J 0
(-3327 4250);
DISPLAY 0.638298 (-3327 4250);
PAINT MONO (-3327 4250);
FORCEPROP 2 LAST CDS_LIB standard
J 0
(-2925 4250);
DISPLAY INVISIBLE (-2925 4250);
FORCEPROP 1 LAST OFFPAGE TRUE
J 2
(-3250 4125);
DISPLAY 0.872340 (-3250 4125);
PAINT GREEN (-3250 4125);
DISPLAY INVISIBLE (-3250 4125);
FORCEPROP 1 LAST COMMENT_BODY TRUE
J 2
(-2900 4150);
DISPLAY 0.872340 (-2900 4150);
PAINT GREEN (-2900 4150);
DISPLAY INVISIBLE (-2900 4150);
FORCEPROP 2 LAST PATH I21
J 0
(-2875 4325);
DISPLAY 0.680851 (-2875 4325);
DISPLAY INVISIBLE (-2875 4325);
FORCEADD OFFPAGE..5
(-3425 4300);
FORCEPROP 2 LAST $XR0 263 
J 0
(-3710 4300);
DISPLAY 0.638298 (-3710 4300);
PAINT MONO (-3710 4300);
FORCEPROP 2 LAST $XR1 85 
J 0
(-3800 4300);
DISPLAY 0.638298 (-3800 4300);
PAINT MONO (-3800 4300);
FORCEPROP 2 LAST CDS_LIB standard
J 0
(-3425 4300);
DISPLAY INVISIBLE (-3425 4300);
FORCEPROP 1 LAST OFFPAGE TRUE
J 0
(-3100 4175);
DISPLAY 0.872340 (-3100 4175);
PAINT AQUA (-3100 4175);
DISPLAY INVISIBLE (-3100 4175);
FORCEPROP 1 LAST COMMENT_BODY TRUE
J 0
(-3325 4225);
DISPLAY 1.170213 (-3325 4225);
PAINT GREEN (-3325 4225);
DISPLAY INVISIBLE (-3325 4225);
FORCEPROP 2 LAST PATH I22
J 0
(-3375 4375);
DISPLAY 0.680851 (-3375 4375);
DISPLAY INVISIBLE (-3375 4375);
FORCEADD UNIVERSAL_GND..1
(-2150 3525);
FORCEPROP 3 LASTPIN (-2150 3575) SIG_NAME GND\g
J 0
(-2140 3585);
DISPLAY 0.659574 (-2140 3585);
PAINT MONO (-2140 3585);
DISPLAY INVISIBLE (-2140 3585);
FORCEPROP 2 LAST CDS_LIB pure_quanta_power
J 0
(-2150 3525);
DISPLAY INVISIBLE (-2150 3525);
FORCEPROP 1 LAST HDL_POWER GND
J 1
(-2125 3450);
DISPLAY 0.872340 (-2125 3450);
PAINT GREEN (-2125 3450);
DISPLAY INVISIBLE (-2125 3450);
FORCEPROP 1 LAST PATH I24
J 0
(-2075 3525);
DISPLAY 0.872340 (-2075 3525);
PAINT AQUA (-2075 3525);
DISPLAY INVISIBLE (-2075 3525);
FORCEADD UNIVERSAL_POWER..1
(-2400 4450);
FORCEPROP 3 LASTPIN (-2400 4400) SIG_NAME P3V3_AUX\g
J 0
(-2390 4410);
DISPLAY 0.659574 (-2390 4410);
PAINT MONO (-2390 4410);
DISPLAY INVISIBLE (-2390 4410);
FORCEPROP 1 LAST HDL_POWER P3V3_AUX
J 1
(-2400 4500);
DISPLAY 0.723404 (-2400 4500);
PAINT GREEN (-2400 4500);
FORCEPROP 2 LAST CDS_LIB pure_quanta_power
J 0
(-2400 4450);
DISPLAY INVISIBLE (-2400 4450);
FORCEPROP 1 LAST PATH I25
J 0
(-2350 4475);
DISPLAY 0.872340 (-2350 4475);
PAINT AQUA (-2350 4475);
DISPLAY INVISIBLE (-2350 4475);
FORCEADD UNIVERSAL_GND..1
(-1300 3675);
FORCEPROP 3 LASTPIN (-1300 3725) SIG_NAME GND\g
J 0
(-1290 3735);
DISPLAY 0.659574 (-1290 3735);
PAINT MONO (-1290 3735);
DISPLAY INVISIBLE (-1290 3735);
FORCEPROP 2 LAST CDS_LIB pure_quanta_power
J 0
(-1300 3675);
DISPLAY INVISIBLE (-1300 3675);
FORCEPROP 1 LAST HDL_POWER GND
J 1
(-1275 3600);
DISPLAY 0.872340 (-1275 3600);
PAINT GREEN (-1275 3600);
DISPLAY INVISIBLE (-1275 3600);
FORCEPROP 1 LAST PATH I26
J 0
(-1225 3675);
DISPLAY 0.872340 (-1225 3675);
PAINT AQUA (-1225 3675);
DISPLAY INVISIBLE (-1225 3675);
FORCEADD UNIVERSAL_GND..1
(-925 3450);
FORCEPROP 3 LASTPIN (-925 3500) SIG_NAME GND\g
J 0
(-915 3510);
DISPLAY 0.659574 (-915 3510);
PAINT MONO (-915 3510);
DISPLAY INVISIBLE (-915 3510);
FORCEPROP 2 LAST CDS_LIB pure_quanta_power
J 0
(-925 3450);
DISPLAY INVISIBLE (-925 3450);
FORCEPROP 1 LAST HDL_POWER GND
J 1
(-900 3375);
DISPLAY 0.872340 (-900 3375);
PAINT GREEN (-900 3375);
DISPLAY INVISIBLE (-900 3375);
FORCEPROP 1 LAST PATH I27
J 0
(-850 3450);
DISPLAY 0.872340 (-850 3450);
PAINT AQUA (-850 3450);
DISPLAY INVISIBLE (-850 3450);
FORCEADD Q_CAP..1
(-925 3625);
FORCEPROP 1 LAST LOCATION PC1789
J 0
(-850 3725);
DISPLAY 0.978723 (-850 3725);
FORCEPROP 0 LAST $SEC 1
J 0
(-850 3775);
DISPLAY 0.680851 (-850 3775);
PAINT MONO (-850 3775);
DISPLAY INVISIBLE (-850 3775);
FORCEPROP 0 LAST CDS_SEC 1
J 0
(-850 3775);
DISPLAY 1.021277 (-850 3775);
DISPLAY INVISIBLE (-850 3775);
FORCEPROP 1 LASTPIN (-925 3725) $PN 1
J 0
(-915 3705);
DISPLAY 0.787234 (-915 3705);
PAINT MONO (-915 3705);
FORCEPROP 1 LASTPIN (-925 3525) $PN 2
J 0
(-915 3505);
DISPLAY 0.787234 (-915 3505);
PAINT MONO (-915 3505);
FORCEPROP 0 LAST ROOM HSC BOM2
J 0
(-850 3825);
DISPLAY 0.680851 (-850 3825);
FORCEPROP 1 LAST VOLTAGE 25V
J 0
(-850 3575);
DISPLAY 0.723404 (-850 3575);
PAINT SKYBLUE (-850 3575);
FORCEPROP 1 LAST MATERIAL X7R
J 0
(-850 3475);
DISPLAY 0.723404 (-850 3475);
PAINT SKYBLUE (-850 3475);
FORCEPROP 1 LAST VALUE 0.1UF
J 0
(-850 3625);
DISPLAY 0.723404 (-850 3625);
PAINT SKYBLUE (-850 3625);
FORCEPROP 1 LAST PACK_TYPE 0402
J 0
(-850 3425);
DISPLAY 0.723404 (-850 3425);
PAINT SKYBLUE (-850 3425);
FORCEPROP 1 LAST TOLERANCE 10%
J 0
(-850 3525);
DISPLAY 0.723404 (-850 3525);
PAINT SKYBLUE (-850 3525);
FORCEPROP 2 LAST CDS_LIB pure_quanta
J 0
(-925 3625);
DISPLAY INVISIBLE (-925 3625);
FORCEPROP 1 LAST PATH I28
J 0
(-875 3775);
DISPLAY 0.978723 (-875 3775);
PAINT WHITE (-875 3775);
DISPLAY INVISIBLE (-875 3775);
FORCEPROP 1 LAST PART_NUMBER CH4104K1B00
J 0
(-850 3675);
DISPLAY 0.723404 (-850 3675);
PAINT SKYBLUE (-850 3675);
DISPLAY INVISIBLE (-850 3675);
FORCEADD UNIVERSAL_POWER..1
(-800 4450);
FORCEPROP 1 LAST HDL_POWER P12V_PSU
J 1
(-800 4500);
DISPLAY 0.723404 (-800 4500);
PAINT GREEN (-800 4500);
FORCEPROP 2 LAST BOM_COST MIO_VRD_SB
J 0
(-800 4550);
DISPLAY 0.617021 (-800 4550);
PAINT PURPLE (-800 4550);
DISPLAY INVISIBLE (-800 4550);
FORCEPROP 2 LAST ROOM AUX_SW
J 0
(-800 4550);
DISPLAY 0.617021 (-800 4550);
DISPLAY INVISIBLE (-800 4550);
FORCEPROP 2 LAST CDS_LIB pure_quanta_power
J 0
(-800 4450);
DISPLAY INVISIBLE (-800 4450);
FORCEPROP 1 LAST PATH I29
J 0
(-750 4475);
DISPLAY 0.872340 (-750 4475);
PAINT AQUA (-750 4475);
DISPLAY INVISIBLE (-750 4475);
FORCEADD Q_RES..1
(-5275 2125);
FORCEPROP 1 LAST LOCATION R2625
J 0
(-5450 2175);
DISPLAY 0.638298 (-5450 2175);
FORCEPROP 0 LAST $SEC 1
J 0
(-5100 2200);
DISPLAY 0.680851 (-5100 2200);
PAINT MONO (-5100 2200);
DISPLAY INVISIBLE (-5100 2200);
FORCEPROP 0 LAST CDS_SEC 1
J 0
(-5225 2300);
DISPLAY 1.021277 (-5225 2300);
DISPLAY INVISIBLE (-5225 2300);
FORCEPROP 1 LASTPIN (-5375 2125) $PN 1
J 0
(-5363 2137);
DISPLAY 0.787234 (-5363 2137);
PAINT MONO (-5363 2137);
FORCEPROP 1 LASTPIN (-5175 2125) $PN 2
J 0
(-5213 2137);
DISPLAY 0.787234 (-5213 2137);
PAINT MONO (-5213 2137);
FORCEPROP 1 LAST VALUE 49.9
J 2
(-5025 2150);
DISPLAY 0.638298 (-5025 2150);
FORCEPROP 0 LAST ROOM HSC BOM2
J 0
(-5275 2200);
DISPLAY 0.553191 (-5275 2200);
FORCEPROP 1 LAST TOLERANCE 1%
J 0
(-5200 2075);
DISPLAY 0.638298 (-5200 2075);
FORCEPROP 1 LAST MATERIAL CHIP
J 0
(-5200 2025);
DISPLAY 0.638298 (-5200 2025);
FORCEPROP 1 LAST PACK_TYPE 0402LF
J 0
(-5475 2025);
DISPLAY 0.638298 (-5475 2025);
FORCEPROP 1 LAST WATTAGE 1/16W
J 2
(-5325 2075);
DISPLAY 0.638298 (-5325 2075);
FORCEPROP 2 LAST CDS_LIB pure_quanta
J 0
(-5275 2125);
DISPLAY INVISIBLE (-5275 2125);
FORCEPROP 1 LAST PATH I3
J 0
(-5325 2275);
DISPLAY 0.978723 (-5325 2275);
PAINT WHITE (-5325 2275);
DISPLAY INVISIBLE (-5325 2275);
FORCEPROP 1 LAST PART_NUMBER CS04992FB07
J 0
(-5475 1975);
DISPLAY 0.638298 (-5475 1975);
DISPLAY INVISIBLE (-5475 1975);
FORCEADD OFFPAGE..2
(-700 3950);
FORCEPROP 2 LAST $XR0 267 
J 0
(-511 3950);
DISPLAY 0.638298 (-511 3950);
PAINT MONO (-511 3950);
FORCEPROP 2 LAST CDS_LIB standard
J 0
(-700 3950);
DISPLAY INVISIBLE (-700 3950);
FORCEPROP 1 LAST OFFPAGE TRUE
J 0
(-375 3825);
DISPLAY 0.872340 (-375 3825);
PAINT AQUA (-375 3825);
DISPLAY INVISIBLE (-375 3825);
FORCEPROP 1 LAST COMMENT_BODY TRUE
J 0
(-745 3855);
DISPLAY 0.872340 (-745 3855);
PAINT GREEN (-745 3855);
DISPLAY INVISIBLE (-745 3855);
FORCEPROP 2 LAST PATH I30
J 0
(-525 4025);
DISPLAY 0.680851 (-525 4025);
DISPLAY INVISIBLE (-525 4025);
FORCEADD OFFPAGE..4
(-700 4050);
FORCEPROP 2 LAST $XR0 267 
J 0
(-514 4050);
DISPLAY 0.638298 (-514 4050);
PAINT MONO (-514 4050);
FORCEPROP 2 LAST CDS_LIB standard
J 0
(-700 4050);
DISPLAY INVISIBLE (-700 4050);
FORCEPROP 1 LAST OFFPAGE TRUE
J 0
(-375 3925);
DISPLAY 0.872340 (-375 3925);
PAINT GREEN (-375 3925);
DISPLAY INVISIBLE (-375 3925);
FORCEPROP 1 LAST COMMENT_BODY TRUE
J 0
(-725 3950);
DISPLAY 0.872340 (-725 3950);
PAINT GREEN (-725 3950);
DISPLAY INVISIBLE (-725 3950);
FORCEPROP 2 LAST PATH I31
J 0
(-525 4125);
DISPLAY 0.680851 (-525 4125);
DISPLAY INVISIBLE (-525 4125);
FORCEADD OFFPAGE..2
(-700 4000);
FORCEPROP 2 LAST $XR0 267 
J 0
(-511 4000);
DISPLAY 0.638298 (-511 4000);
PAINT MONO (-511 4000);
FORCEPROP 2 LAST CDS_LIB standard
J 0
(-700 4000);
DISPLAY INVISIBLE (-700 4000);
FORCEPROP 1 LAST OFFPAGE TRUE
J 0
(-375 3875);
DISPLAY 0.872340 (-375 3875);
PAINT AQUA (-375 3875);
DISPLAY INVISIBLE (-375 3875);
FORCEPROP 1 LAST COMMENT_BODY TRUE
J 0
(-745 3905);
DISPLAY 0.872340 (-745 3905);
PAINT GREEN (-745 3905);
DISPLAY INVISIBLE (-745 3905);
FORCEPROP 2 LAST PATH I32
J 0
(-525 4075);
DISPLAY 0.680851 (-525 4075);
DISPLAY INVISIBLE (-525 4075);
FORCEADD OFFPAGE..4
(-700 4100);
FORCEPROP 2 LAST $XR0 267 
J 0
(-514 4100);
DISPLAY 0.638298 (-514 4100);
PAINT MONO (-514 4100);
FORCEPROP 2 LAST CDS_LIB standard
J 0
(-700 4100);
DISPLAY INVISIBLE (-700 4100);
FORCEPROP 1 LAST OFFPAGE TRUE
J 0
(-375 3975);
DISPLAY 0.872340 (-375 3975);
PAINT GREEN (-375 3975);
DISPLAY INVISIBLE (-375 3975);
FORCEPROP 1 LAST COMMENT_BODY TRUE
J 0
(-725 4000);
DISPLAY 0.872340 (-725 4000);
PAINT GREEN (-725 4000);
DISPLAY INVISIBLE (-725 4000);
FORCEPROP 2 LAST PATH I33
J 0
(-525 4175);
DISPLAY 0.680851 (-525 4175);
DISPLAY INVISIBLE (-525 4175);
FORCEADD UNIVERSAL_POWER..1
(-175 3950);
FORCEPROP 1 LAST HDL_POWER P12V_AUX
J 1
(-175 4000);
DISPLAY 0.702128 (-175 4000);
PAINT GREEN (-175 4000);
FORCEPROP 2 LAST CDS_LIB pure_quanta_power
J 0
(-175 3950);
DISPLAY INVISIBLE (-175 3950);
FORCEPROP 1 LAST PATH I34
J 0
(-125 3975);
DISPLAY 0.872340 (-125 3975);
PAINT AQUA (-125 3975);
DISPLAY INVISIBLE (-125 3975);
FORCEADD OFFPAGE..4
(-700 4200);
FORCEPROP 2 LAST $XR0 267 
J 0
(-514 4200);
DISPLAY 0.638298 (-514 4200);
PAINT MONO (-514 4200);
FORCEPROP 2 LAST CDS_LIB standard
J 0
(-700 4200);
DISPLAY INVISIBLE (-700 4200);
FORCEPROP 1 LAST OFFPAGE TRUE
J 0
(-375 4075);
DISPLAY 0.872340 (-375 4075);
PAINT GREEN (-375 4075);
DISPLAY INVISIBLE (-375 4075);
FORCEPROP 1 LAST COMMENT_BODY TRUE
J 0
(-725 4100);
DISPLAY 0.872340 (-725 4100);
PAINT GREEN (-725 4100);
DISPLAY INVISIBLE (-725 4100);
FORCEPROP 2 LAST PATH I35
J 0
(-525 4275);
DISPLAY 0.680851 (-525 4275);
DISPLAY INVISIBLE (-525 4275);
FORCEADD OFFPAGE..4
(-700 4150);
FORCEPROP 2 LAST $XR0 267 
J 0
(-514 4150);
DISPLAY 0.638298 (-514 4150);
PAINT MONO (-514 4150);
FORCEPROP 2 LAST CDS_LIB standard
J 0
(-700 4150);
DISPLAY INVISIBLE (-700 4150);
FORCEPROP 1 LAST OFFPAGE TRUE
J 0
(-375 4025);
DISPLAY 0.872340 (-375 4025);
PAINT GREEN (-375 4025);
DISPLAY INVISIBLE (-375 4025);
FORCEPROP 1 LAST COMMENT_BODY TRUE
J 0
(-725 4050);
DISPLAY 0.872340 (-725 4050);
PAINT GREEN (-725 4050);
DISPLAY INVISIBLE (-725 4050);
FORCEPROP 2 LAST PATH I36
J 0
(-525 4225);
DISPLAY 0.680851 (-525 4225);
DISPLAY INVISIBLE (-525 4225);
FORCEADD OFFPAGE..4
(-700 4250);
FORCEPROP 2 LAST $XR0 267 
J 0
(-514 4250);
DISPLAY 0.638298 (-514 4250);
PAINT MONO (-514 4250);
FORCEPROP 2 LAST CDS_LIB standard
J 0
(-700 4250);
DISPLAY INVISIBLE (-700 4250);
FORCEPROP 1 LAST OFFPAGE TRUE
J 0
(-375 4125);
DISPLAY 0.872340 (-375 4125);
PAINT GREEN (-375 4125);
DISPLAY INVISIBLE (-375 4125);
FORCEPROP 1 LAST COMMENT_BODY TRUE
J 0
(-725 4150);
DISPLAY 0.872340 (-725 4150);
PAINT GREEN (-725 4150);
DISPLAY INVISIBLE (-725 4150);
FORCEPROP 2 LAST PATH I37
J 0
(-525 4325);
DISPLAY 0.680851 (-525 4325);
DISPLAY INVISIBLE (-525 4325);
FORCEADD OFFPAGE..4
(-700 4300);
FORCEPROP 2 LAST $XR0 267 
J 0
(-514 4300);
DISPLAY 0.638298 (-514 4300);
PAINT MONO (-514 4300);
FORCEPROP 2 LAST CDS_LIB standard
J 0
(-700 4300);
DISPLAY INVISIBLE (-700 4300);
FORCEPROP 1 LAST OFFPAGE TRUE
J 0
(-375 4175);
DISPLAY 0.872340 (-375 4175);
PAINT GREEN (-375 4175);
DISPLAY INVISIBLE (-375 4175);
FORCEPROP 1 LAST COMMENT_BODY TRUE
J 0
(-725 4200);
DISPLAY 0.872340 (-725 4200);
PAINT GREEN (-725 4200);
DISPLAY INVISIBLE (-725 4200);
FORCEPROP 2 LAST PATH I38
J 0
(-525 4375);
DISPLAY 0.680851 (-525 4375);
DISPLAY INVISIBLE (-525 4375);
FORCEADD Q_RES..1
(-2500 2125);
FORCEPROP 1 LAST LOCATION R2627
J 0
(-2700 2125);
DISPLAY 0.553191 (-2700 2125);
FORCEPROP 0 LAST $SEC 1
J 0
(-2400 2200);
DISPLAY 0.680851 (-2400 2200);
PAINT MONO (-2400 2200);
DISPLAY INVISIBLE (-2400 2200);
FORCEPROP 0 LAST CDS_SEC 1
J 0
(-2400 2200);
DISPLAY 1.021277 (-2400 2200);
DISPLAY INVISIBLE (-2400 2200);
FORCEPROP 1 LASTPIN (-2600 2125) $PN 1
J 0
(-2588 2137);
DISPLAY 0.808511 (-2588 2137);
PAINT WHITE (-2588 2137);
FORCEPROP 1 LASTPIN (-2400 2125) $PN 2
J 0
(-2438 2137);
DISPLAY 0.808511 (-2438 2137);
PAINT WHITE (-2438 2137);
FORCEPROP 0 LAST ROOM HSC BOM2
J 0
(-2375 2150);
DISPLAY 0.446809 (-2375 2150);
FORCEPROP 1 LAST MATERIAL CHIP
J 0
(-2275 2125);
DISPLAY 0.404255 (-2275 2125);
FORCEPROP 1 LAST WATTAGE 1/16W
J 2
(-2375 2100);
DISPLAY 0.319149 (-2375 2100);
FORCEPROP 1 LAST VALUE 0
J 2
(-2350 2125);
DISPLAY 0.404255 (-2350 2125);
FORCEPROP 1 LAST PACK_TYPE 0402LF
J 0
(-2625 2100);
DISPLAY 0.319149 (-2625 2100);
FORCEPROP 1 LAST TOLERANCE 5%
J 0
(-2325 2125);
DISPLAY 0.404255 (-2325 2125);
FORCEPROP 2 LAST CDS_LIB pure_quanta
J 0
(-2500 2125);
DISPLAY INVISIBLE (-2500 2125);
FORCEPROP 1 LAST PATH I39
J 0
(-2550 2275);
DISPLAY 0.978723 (-2550 2275);
PAINT WHITE (-2550 2275);
DISPLAY INVISIBLE (-2550 2275);
FORCEPROP 1 LAST PART_NUMBER CS00002JB13
J 0
(-2625 2075);
DISPLAY 0.319149 (-2625 2075);
DISPLAY INVISIBLE (-2625 2075);
FORCEADD Q_CAP..1
R 2
(-4975 1975);
FORCEPROP 1 LAST LOCATION C1786
J 0
(-4900 2075);
DISPLAY 0.510638 (-4900 2075);
FORCEPROP 0 LAST $SEC 1
J 0
(-4900 2100);
DISPLAY 0.680851 (-4900 2100);
PAINT MONO (-4900 2100);
DISPLAY INVISIBLE (-4900 2100);
FORCEPROP 0 LAST CDS_SEC 1
J 0
(-5025 2125);
DISPLAY 1.021277 (-5025 2125);
DISPLAY INVISIBLE (-5025 2125);
FORCEPROP 1 LASTPIN (-4975 2075) $PN 1
J 2
(-4985 2055);
DISPLAY 0.787234 (-4985 2055);
PAINT MONO (-4985 2055);
FORCEPROP 1 LASTPIN (-4975 1875) $PN 2
J 2
(-4985 1855);
DISPLAY 0.787234 (-4985 1855);
PAINT MONO (-4985 1855);
FORCEPROP 1 LAST VALUE 1000PF
J 0
(-4900 2025);
DISPLAY 0.510638 (-4900 2025);
FORCEPROP 1 LAST VOLTAGE 50V
J 0
(-4900 1975);
DISPLAY 0.510638 (-4900 1975);
FORCEPROP 1 LAST TOLERANCE 10%
J 0
(-4900 1925);
DISPLAY 0.510638 (-4900 1925);
FORCEPROP 1 LAST MATERIAL X7R
J 0
(-4900 1875);
DISPLAY 0.510638 (-4900 1875);
FORCEPROP 0 LAST ROOM HSC BOM2
J 0
(-4900 1725);
DISPLAY 0.553191 (-4900 1725);
FORCEPROP 1 LAST PACK_TYPE 0603
J 0
(-4900 1775);
DISPLAY 0.510638 (-4900 1775);
FORCEPROP 2 LAST CDS_LIB pure_quanta
J 0
(-4975 1975);
DISPLAY INVISIBLE (-4975 1975);
FORCEPROP 1 LAST PATH I4
J 2
(-5025 2125);
DISPLAY 0.978723 (-5025 2125);
PAINT WHITE (-5025 2125);
DISPLAY INVISIBLE (-5025 2125);
FORCEPROP 1 LAST PART_NUMBER TMP_QCH21006K917
J 0
(-4900 1825);
DISPLAY 0.510638 (-4900 1825);
DISPLAY INVISIBLE (-4900 1825);
FORCEADD Q_RES..1
(-2500 2225);
FORCEPROP 1 LAST LOCATION R2626
J 0
(-2700 2225);
DISPLAY 0.553191 (-2700 2225);
FORCEPROP 0 LAST $SEC 1
J 0
(-2400 2300);
DISPLAY 0.680851 (-2400 2300);
PAINT MONO (-2400 2300);
DISPLAY INVISIBLE (-2400 2300);
FORCEPROP 0 LAST CDS_SEC 1
J 0
(-2400 2300);
DISPLAY 1.021277 (-2400 2300);
DISPLAY INVISIBLE (-2400 2300);
FORCEPROP 1 LASTPIN (-2600 2225) $PN 1
J 0
(-2588 2237);
DISPLAY 0.808511 (-2588 2237);
PAINT WHITE (-2588 2237);
FORCEPROP 1 LASTPIN (-2400 2225) $PN 2
J 0
(-2438 2237);
DISPLAY 0.808511 (-2438 2237);
PAINT WHITE (-2438 2237);
FORCEPROP 0 LAST ROOM HSC BOM2
J 0
(-2375 2250);
DISPLAY 0.446809 (-2375 2250);
FORCEPROP 1 LAST WATTAGE 1/16W
J 2
(-2375 2200);
DISPLAY 0.319149 (-2375 2200);
FORCEPROP 1 LAST TOLERANCE 5%
J 0
(-2325 2225);
DISPLAY 0.404255 (-2325 2225);
FORCEPROP 1 LAST MATERIAL CHIP
J 0
(-2275 2225);
DISPLAY 0.404255 (-2275 2225);
FORCEPROP 1 LAST PACK_TYPE 0402LF
J 0
(-2625 2200);
DISPLAY 0.319149 (-2625 2200);
FORCEPROP 1 LAST VALUE 0
J 2
(-2350 2225);
DISPLAY 0.404255 (-2350 2225);
FORCEPROP 2 LAST CDS_LIB pure_quanta
J 0
(-2500 2225);
DISPLAY INVISIBLE (-2500 2225);
FORCEPROP 1 LAST PATH I40
J 0
(-2550 2375);
DISPLAY 0.978723 (-2550 2375);
PAINT WHITE (-2550 2375);
DISPLAY INVISIBLE (-2550 2375);
FORCEPROP 1 LAST PART_NUMBER CS00002JB13
J 0
(-2625 2175);
DISPLAY 0.319149 (-2625 2175);
DISPLAY INVISIBLE (-2625 2175);
FORCEADD SCONN21_9193031121LF..1
R 2
(-1700 4025);
FORCEPROP 1 LAST LOCATION PJ38
J 2
(-1556 4731);
DISPLAY 0.723404 (-1556 4731);
PAINT GREEN (-1556 4731);
FORCEPROP 2 LAST SEC 1
J 0
(-1575 4875);
DISPLAY 0.680851 (-1575 4875);
PAINT MONO (-1575 4875);
DISPLAY INVISIBLE (-1575 4875);
FORCEPROP 2 LASTPIN (-1400 4350) $PN 1
J 0
(-1390 4360);
DISPLAY 0.680851 (-1390 4360);
PAINT MONO (-1390 4360);
FORCEPROP 2 LASTPIN (-1400 4300) $PN 2
J 0
(-1390 4310);
DISPLAY 0.680851 (-1390 4310);
PAINT MONO (-1390 4310);
FORCEPROP 2 LASTPIN (-1400 4250) $PN 3
J 0
(-1390 4260);
DISPLAY 0.680851 (-1390 4260);
PAINT MONO (-1390 4260);
FORCEPROP 2 LASTPIN (-1400 4200) $PN 4
J 0
(-1390 4210);
DISPLAY 0.680851 (-1390 4210);
PAINT MONO (-1390 4210);
FORCEPROP 2 LASTPIN (-1400 4150) $PN 5
J 0
(-1390 4160);
DISPLAY 0.680851 (-1390 4160);
PAINT MONO (-1390 4160);
FORCEPROP 2 LASTPIN (-1400 4100) $PN 6
J 0
(-1390 4110);
DISPLAY 0.680851 (-1390 4110);
PAINT MONO (-1390 4110);
FORCEPROP 2 LASTPIN (-1400 4050) $PN 7
J 0
(-1390 4060);
DISPLAY 0.680851 (-1390 4060);
PAINT MONO (-1390 4060);
FORCEPROP 2 LASTPIN (-1400 4000) $PN 8
J 0
(-1390 4010);
DISPLAY 0.680851 (-1390 4010);
PAINT MONO (-1390 4010);
FORCEPROP 2 LASTPIN (-1400 3950) $PN 9
J 0
(-1390 3960);
DISPLAY 0.680851 (-1390 3960);
PAINT MONO (-1390 3960);
FORCEPROP 2 LASTPIN (-1400 3900) $PN 10
J 0
(-1390 3910);
DISPLAY 0.680851 (-1390 3910);
PAINT MONO (-1390 3910);
FORCEPROP 2 LASTPIN (-1400 3850) $PN 11
J 0
(-1390 3860);
DISPLAY 0.680851 (-1390 3860);
PAINT MONO (-1390 3860);
FORCEPROP 2 LASTPIN (-2000 4350) $PN 12
J 2
(-2010 4360);
DISPLAY 0.680851 (-2010 4360);
PAINT MONO (-2010 4360);
FORCEPROP 2 LASTPIN (-2000 4300) $PN 13
J 2
(-2010 4310);
DISPLAY 0.680851 (-2010 4310);
PAINT MONO (-2010 4310);
FORCEPROP 2 LASTPIN (-2000 4250) $PN 14
J 2
(-2010 4260);
DISPLAY 0.680851 (-2010 4260);
PAINT MONO (-2010 4260);
FORCEPROP 2 LASTPIN (-2000 4200) $PN 15
J 2
(-2010 4210);
DISPLAY 0.680851 (-2010 4210);
PAINT MONO (-2010 4210);
FORCEPROP 2 LASTPIN (-2000 4150) $PN 16
J 2
(-2010 4160);
DISPLAY 0.680851 (-2010 4160);
PAINT MONO (-2010 4160);
FORCEPROP 2 LASTPIN (-2000 4100) $PN 17
J 2
(-2010 4110);
DISPLAY 0.680851 (-2010 4110);
PAINT MONO (-2010 4110);
FORCEPROP 2 LASTPIN (-2000 4050) $PN 18
J 2
(-2010 4060);
DISPLAY 0.680851 (-2010 4060);
PAINT MONO (-2010 4060);
FORCEPROP 2 LASTPIN (-2000 4000) $PN 19
J 2
(-2010 4010);
DISPLAY 0.680851 (-2010 4010);
PAINT MONO (-2010 4010);
FORCEPROP 2 LASTPIN (-2000 3950) $PN 20
J 2
(-2010 3960);
DISPLAY 0.680851 (-2010 3960);
PAINT MONO (-2010 3960);
FORCEPROP 2 LASTPIN (-2000 3900) $PN 21
J 2
(-2010 3910);
DISPLAY 0.680851 (-2010 3910);
PAINT MONO (-2010 3910);
FORCEPROP 2 LASTPIN (-2000 3750) $PN G1
J 2
(-2010 3760);
DISPLAY 0.680851 (-2010 3760);
PAINT MONO (-2010 3760);
FORCEPROP 2 LASTPIN (-2000 3700) $PN G2
J 2
(-2010 3710);
DISPLAY 0.680851 (-2010 3710);
PAINT MONO (-2010 3710);
FORCEPROP 1 LAST MATERIAL IO
J 2
(-1556 4457);
DISPLAY 0.723404 (-1556 4457);
PAINT GREEN (-1556 4457);
FORCEPROP 0 LAST ROOM HSC BOM2
J 0
(-1825 4875);
DISPLAY 0.680851 (-1825 4875);
FORCEPROP 2 LAST PART_TYPE SMLF
J 2
(-1575 4825);
DISPLAY 0.680851 (-1575 4825);
FORCEPROP 2 LAST VALUE SCONN21_91930-31121LF
J 2
(-1575 4775);
DISPLAY 0.680851 (-1575 4775);
FORCEPROP 2 LAST SEC_TYPE 
J 0
(-1575 4875);
DISPLAY 0.680851 (-1575 4875);
DISPLAY INVISIBLE (-1575 4875);
FORCEPROP 2 LAST CDS_LIB pure_quanta
J 2
(-1700 4025);
DISPLAY INVISIBLE (-1700 4025);
FORCEPROP 1 LAST NEEDS_NO_SIZE TRUE
J 2
(-1700 4025);
DISPLAY 0.723404 (-1700 4025);
PAINT GREEN (-1700 4025);
DISPLAY INVISIBLE (-1700 4025);
FORCEPROP 1 LAST CDS_LMAN_SYM_OUTLINE -150,425,150,-425
J 2
(-1700 4025);
DISPLAY 0.468085 (-1700 4025);
PAINT GREEN (-1700 4025);
DISPLAY INVISIBLE (-1700 4025);
FORCEPROP 1 LAST PATH I42
J 2
(-1700 4025);
DISPLAY 0.723404 (-1700 4025);
PAINT GREEN (-1700 4025);
DISPLAY INVISIBLE (-1700 4025);
FORCEPROP 1 LAST PART_NUMBER DFHS21FS003
J 2
(-1556 4584);
DISPLAY 0.723404 (-1556 4584);
PAINT GREEN (-1556 4584);
DISPLAY INVISIBLE (-1556 4584);
FORCEADD OFFPAGE..5
(-2925 4150);
FORCEPROP 2 LAST $XR0 268 
J 0
(-3210 4150);
DISPLAY 0.638298 (-3210 4150);
PAINT MONO (-3210 4150);
FORCEPROP 2 LAST CDS_LIB standard
J 0
(-2925 4150);
DISPLAY INVISIBLE (-2925 4150);
FORCEPROP 1 LAST OFFPAGE TRUE
J 0
(-2600 4025);
DISPLAY 0.872340 (-2600 4025);
PAINT AQUA (-2600 4025);
DISPLAY INVISIBLE (-2600 4025);
FORCEPROP 1 LAST COMMENT_BODY TRUE
J 0
(-2825 4075);
DISPLAY 1.170213 (-2825 4075);
PAINT GREEN (-2825 4075);
DISPLAY INVISIBLE (-2825 4075);
FORCEPROP 2 LAST PATH I44
J 0
(-2875 4225);
DISPLAY 0.680851 (-2875 4225);
DISPLAY INVISIBLE (-2875 4225);
FORCEADD Q_RES..2
R 2
(-1450 2825);
FORCEPROP 1 LAST LOCATION R6230
J 2
(-1495 2950);
DISPLAY 0.638298 (-1495 2950);
FORCEPROP 0 LAST $SEC 1
J 0
(-1475 3000);
DISPLAY 0.680851 (-1475 3000);
PAINT MONO (-1475 3000);
DISPLAY INVISIBLE (-1475 3000);
FORCEPROP 0 LAST CDS_SEC 1
J 0
(-1475 3000);
DISPLAY 0.680851 (-1475 3000);
DISPLAY INVISIBLE (-1475 3000);
FORCEPROP 1 LASTPIN (-1450 2925) $PN 1
J 2
(-1455 2887);
DISPLAY 0.787234 (-1455 2887);
PAINT MONO (-1455 2887);
FORCEPROP 1 LASTPIN (-1450 2725) $PN 2
J 2
(-1455 2735);
DISPLAY 0.787234 (-1455 2735);
PAINT MONO (-1455 2735);
FORCEPROP 1 LAST TOLERANCE 5%
J 2
(-1495 2850);
DISPLAY 0.638298 (-1495 2850);
FORCEPROP 1 LAST PACK_TYPE 0402LF
J 2
(-1490 2650);
DISPLAY 0.638298 (-1490 2650);
FORCEPROP 1 LAST MATERIAL CHIP
J 2
(-1490 2750);
DISPLAY 0.638298 (-1490 2750);
FORCEPROP 1 LAST WATTAGE 1/16W
J 2
(-1490 2800);
DISPLAY 0.638298 (-1490 2800);
FORCEPROP 1 LAST VALUE 2.2K
J 2
(-1495 2900);
DISPLAY 0.638298 (-1495 2900);
FORCEPROP 0 LAST ROOM HSC BOM2
J 0
(-1750 3000);
DISPLAY 0.680851 (-1750 3000);
FORCEPROP 2 LAST CDS_LIB pure_quanta
J 2
(-1450 2825);
DISPLAY INVISIBLE (-1450 2825);
FORCEPROP 1 LAST PATH I45
J 2
(-1500 3000);
DISPLAY 0.978723 (-1500 3000);
PAINT WHITE (-1500 3000);
DISPLAY INVISIBLE (-1500 3000);
FORCEPROP 1 LAST PART_NUMBER CS22202JB07
J 2
(-1490 2700);
DISPLAY 0.638298 (-1490 2700);
DISPLAY INVISIBLE (-1490 2700);
FORCEADD Q_RES..2
(-1325 2850);
FORCEPROP 1 LAST LOCATION R6231
J 0
(-1280 2975);
DISPLAY 0.638298 (-1280 2975);
FORCEPROP 0 LAST $SEC 1
J 0
(-1275 3025);
DISPLAY 0.680851 (-1275 3025);
PAINT MONO (-1275 3025);
DISPLAY INVISIBLE (-1275 3025);
FORCEPROP 0 LAST CDS_SEC 1
J 0
(-1275 3025);
DISPLAY 0.680851 (-1275 3025);
DISPLAY INVISIBLE (-1275 3025);
FORCEPROP 1 LASTPIN (-1325 2950) $PN 1
J 0
(-1320 2912);
DISPLAY 0.787234 (-1320 2912);
PAINT MONO (-1320 2912);
FORCEPROP 1 LASTPIN (-1325 2750) $PN 2
J 0
(-1320 2760);
DISPLAY 0.787234 (-1320 2760);
PAINT MONO (-1320 2760);
FORCEPROP 1 LAST PACK_TYPE 0402LF
J 0
(-1285 2675);
DISPLAY 0.638298 (-1285 2675);
FORCEPROP 1 LAST MATERIAL CHIP
J 0
(-1285 2775);
DISPLAY 0.638298 (-1285 2775);
FORCEPROP 1 LAST VALUE 2.2K
J 0
(-1280 2925);
DISPLAY 0.638298 (-1280 2925);
FORCEPROP 0 LAST ROOM HSC BOM2
J 0
(-1275 3025);
DISPLAY 0.680851 (-1275 3025);
FORCEPROP 1 LAST WATTAGE 1/16W
J 0
(-1285 2825);
DISPLAY 0.638298 (-1285 2825);
FORCEPROP 1 LAST TOLERANCE 5%
J 0
(-1280 2875);
DISPLAY 0.638298 (-1280 2875);
FORCEPROP 2 LAST CDS_LIB pure_quanta
J 0
(-1325 2850);
DISPLAY INVISIBLE (-1325 2850);
FORCEPROP 1 LAST PATH I46
J 0
(-1275 3025);
DISPLAY 0.978723 (-1275 3025);
PAINT WHITE (-1275 3025);
DISPLAY INVISIBLE (-1275 3025);
FORCEPROP 1 LAST PART_NUMBER CS22202JB07
J 0
(-1285 2725);
DISPLAY 0.638298 (-1285 2725);
DISPLAY INVISIBLE (-1285 2725);
FORCEADD UNIVERSAL_POWER..1
(-1450 3100);
FORCEPROP 3 LASTPIN (-1450 3050) SIG_NAME P3V3_AUX\g
J 0
(-1440 3060);
DISPLAY 0.659574 (-1440 3060);
PAINT MONO (-1440 3060);
DISPLAY INVISIBLE (-1440 3060);
FORCEPROP 1 LAST HDL_POWER P3V3_AUX
J 1
(-1450 3150);
DISPLAY 0.723404 (-1450 3150);
PAINT GREEN (-1450 3150);
FORCEPROP 2 LAST CDS_LIB pure_quanta_power
J 0
(-1450 3100);
DISPLAY INVISIBLE (-1450 3100);
FORCEPROP 1 LAST PATH I47
J 0
(-1400 3125);
DISPLAY 0.872340 (-1400 3125);
PAINT AQUA (-1400 3125);
DISPLAY INVISIBLE (-1400 3125);
FORCEADD OFFPAGE..5
R 2
(-450 2600);
FORCEPROP 2 LAST $XR1 268 
J 0
(-141 2600);
DISPLAY 0.638298 (-141 2600);
PAINT MONO (-141 2600);
FORCEPROP 2 LAST $XR0 253 
J 0
(-261 2600);
DISPLAY 0.638298 (-261 2600);
PAINT MONO (-261 2600);
FORCEPROP 2 LAST CDS_LIB standard
J 0
(-450 2600);
DISPLAY INVISIBLE (-450 2600);
FORCEPROP 1 LAST OFFPAGE TRUE
J 2
(-775 2475);
DISPLAY 0.872340 (-775 2475);
PAINT GREEN (-775 2475);
DISPLAY INVISIBLE (-775 2475);
FORCEPROP 1 LAST COMMENT_BODY TRUE
J 2
(-550 2525);
DISPLAY 0.872340 (-550 2525);
PAINT PEACH (-550 2525);
DISPLAY INVISIBLE (-550 2525);
FORCEPROP 2 LAST PATH I48
J 0
(-275 2675);
DISPLAY 0.680851 (-275 2675);
DISPLAY INVISIBLE (-275 2675);
FORCEADD OFFPAGE..5
R 2
(-450 2500);
FORCEPROP 2 LAST $XR1 268 
J 0
(-141 2500);
DISPLAY 0.638298 (-141 2500);
PAINT MONO (-141 2500);
FORCEPROP 2 LAST $XR0 253 
J 0
(-261 2500);
DISPLAY 0.638298 (-261 2500);
PAINT MONO (-261 2500);
FORCEPROP 2 LAST CDS_LIB standard
J 0
(-450 2500);
DISPLAY INVISIBLE (-450 2500);
FORCEPROP 1 LAST OFFPAGE TRUE
J 2
(-775 2375);
DISPLAY 0.872340 (-775 2375);
PAINT GREEN (-775 2375);
DISPLAY INVISIBLE (-775 2375);
FORCEPROP 1 LAST COMMENT_BODY TRUE
J 2
(-550 2425);
DISPLAY 0.872340 (-550 2425);
PAINT PEACH (-550 2425);
DISPLAY INVISIBLE (-550 2425);
FORCEPROP 2 LAST PATH I49
J 0
(-275 2575);
DISPLAY 0.680851 (-275 2575);
DISPLAY INVISIBLE (-275 2575);
FORCEADD UNIVERSAL_GND..1
(-4750 2250);
FORCEPROP 3 LASTPIN (-4750 2300) SIG_NAME GND\g
J 0
(-4740 2310);
DISPLAY 0.659574 (-4740 2310);
PAINT MONO (-4740 2310);
DISPLAY INVISIBLE (-4740 2310);
FORCEPROP 2 LAST CDS_LIB pure_quanta_power
J 0
(-4750 2250);
DISPLAY INVISIBLE (-4750 2250);
FORCEPROP 1 LAST HDL_POWER GND
J 1
(-4725 2175);
DISPLAY 0.702128 (-4725 2175);
PAINT GREEN (-4725 2175);
DISPLAY INVISIBLE (-4725 2175);
FORCEPROP 1 LAST PATH I5
J 0
(-4675 2250);
DISPLAY 0.872340 (-4675 2250);
PAINT AQUA (-4675 2250);
DISPLAY INVISIBLE (-4675 2250);
FORCEADD LT6700CS61TRPBF..1
(-5500 5800);
FORCEPROP 1 LAST LOCATION U142
J 0
(-5719 6231);
DISPLAY 0.723404 (-5719 6231);
PAINT GREEN (-5719 6231);
FORCEPROP 2 LAST SEC 1
J 0
(-5700 6375);
DISPLAY 0.680851 (-5700 6375);
PAINT MONO (-5700 6375);
DISPLAY INVISIBLE (-5700 6375);
FORCEPROP 2 LASTPIN (-5125 5700) $PN 2
J 0
(-5115 5710);
DISPLAY 0.680851 (-5115 5710);
PAINT MONO (-5115 5710);
FORCEPROP 2 LASTPIN (-5875 5850) $PN 3
J 2
(-5885 5860);
DISPLAY 0.680851 (-5885 5860);
PAINT MONO (-5885 5860);
FORCEPROP 2 LASTPIN (-5875 5750) $PN 4
J 2
(-5885 5760);
DISPLAY 0.680851 (-5885 5760);
PAINT MONO (-5885 5760);
FORCEPROP 2 LASTPIN (-5125 5850) $PN 1
J 0
(-5115 5860);
DISPLAY 0.680851 (-5115 5860);
PAINT MONO (-5115 5860);
FORCEPROP 2 LASTPIN (-5125 5750) $PN 6
J 0
(-5115 5760);
DISPLAY 0.680851 (-5115 5760);
PAINT MONO (-5115 5760);
FORCEPROP 2 LASTPIN (-5875 5900) $PN 5
J 2
(-5885 5910);
DISPLAY 0.680851 (-5885 5910);
PAINT MONO (-5885 5910);
FORCEPROP 0 LAST ROOM HSC BOM2
J 0
(-5700 6425);
DISPLAY 0.680851 (-5700 6425);
FORCEPROP 2 LAST PART_TYPE SMLF
J 0
(-5700 6325);
DISPLAY 0.680851 (-5700 6325);
FORCEPROP 2 LAST VALUE LT6700CS6-1#TRPBF
J 0
(-5700 6275);
DISPLAY 0.680851 (-5700 6275);
FORCEPROP 1 LAST MATERIAL EMPTY
J 0
(-5719 5957);
DISPLAY 0.723404 (-5719 5957);
PAINT GREEN (-5719 5957);
FORCEPROP 2 LAST SEC_TYPE 
J 0
(-5700 6375);
DISPLAY 0.680851 (-5700 6375);
DISPLAY INVISIBLE (-5700 6375);
FORCEPROP 2 LAST CDS_LIB pure_quanta
J 0
(-5500 5800);
DISPLAY INVISIBLE (-5500 5800);
FORCEPROP 1 LAST CDS_LMAN_SYM_OUTLINE -225,150,225,-150
J 0
(-5500 5800);
DISPLAY 0.468085 (-5500 5800);
PAINT GREEN (-5500 5800);
DISPLAY INVISIBLE (-5500 5800);
FORCEPROP 1 LAST NEEDS_NO_SIZE TRUE
J 0
(-5500 5800);
DISPLAY 0.723404 (-5500 5800);
PAINT GREEN (-5500 5800);
DISPLAY INVISIBLE (-5500 5800);
FORCEPROP 1 LAST PATH I50
J 0
(-5500 5800);
DISPLAY 0.723404 (-5500 5800);
PAINT GREEN (-5500 5800);
DISPLAY INVISIBLE (-5500 5800);
FORCEPROP 1 LAST PART_NUMBER AL006700001
J 0
(-5719 6084);
DISPLAY 0.723404 (-5719 6084);
PAINT GREEN (-5719 6084);
DISPLAY INVISIBLE (-5719 6084);
FORCEADD Q_RES..2
(-7300 6225);
FORCEPROP 1 LAST LOCATION R6234
J 0
(-7255 6350);
DISPLAY 1.021277 (-7255 6350);
FORCEPROP 0 LAST $SEC 1
J 0
(-7250 6400);
DISPLAY 0.680851 (-7250 6400);
PAINT MONO (-7250 6400);
DISPLAY INVISIBLE (-7250 6400);
FORCEPROP 0 LAST CDS_SEC 1
J 0
(-7250 6400);
DISPLAY 0.680851 (-7250 6400);
DISPLAY INVISIBLE (-7250 6400);
FORCEPROP 1 LASTPIN (-7300 6325) $PN 1
J 0
(-7295 6287);
DISPLAY 0.787234 (-7295 6287);
PAINT MONO (-7295 6287);
FORCEPROP 1 LASTPIN (-7300 6125) $PN 2
J 0
(-7295 6135);
DISPLAY 0.787234 (-7295 6135);
PAINT MONO (-7295 6135);
FORCEPROP 1 LAST TOLERANCE 1%
J 0
(-7255 6250);
DISPLAY 0.638298 (-7255 6250);
FORCEPROP 0 LAST ROOM HSC BOM2
J 0
(-7250 6450);
DISPLAY 0.680851 (-7250 6450);
FORCEPROP 1 LAST VALUE 160K
J 0
(-7255 6300);
DISPLAY 0.638298 (-7255 6300);
FORCEPROP 1 LAST WATTAGE 1/16W
J 0
(-7260 6200);
DISPLAY 0.638298 (-7260 6200);
FORCEPROP 1 LAST MATERIAL EMPTY
J 0
(-7260 6150);
DISPLAY 0.638298 (-7260 6150);
FORCEPROP 1 LAST PACK_TYPE 0402LF
J 0
(-7260 6050);
DISPLAY 0.638298 (-7260 6050);
FORCEPROP 2 LAST CDS_LIB pure_quanta
J 0
(-7300 6225);
DISPLAY INVISIBLE (-7300 6225);
FORCEPROP 1 LAST PATH I55
J 0
(-7250 6400);
DISPLAY 0.978723 (-7250 6400);
PAINT WHITE (-7250 6400);
DISPLAY INVISIBLE (-7250 6400);
FORCEPROP 1 LAST PART_NUMBER CS41602FB05
J 0
(-7260 6100);
DISPLAY 0.638298 (-7260 6100);
DISPLAY INVISIBLE (-7260 6100);
FORCEADD Q_RES..2
(-7775 6200);
FORCEPROP 1 LAST LOCATION R6232
J 0
(-7730 6325);
DISPLAY 0.978723 (-7730 6325);
FORCEPROP 0 LAST $SEC 1
J 0
(-7725 6375);
DISPLAY 0.680851 (-7725 6375);
PAINT MONO (-7725 6375);
DISPLAY INVISIBLE (-7725 6375);
FORCEPROP 0 LAST CDS_SEC 1
J 0
(-7725 6375);
DISPLAY 0.680851 (-7725 6375);
DISPLAY INVISIBLE (-7725 6375);
FORCEPROP 1 LASTPIN (-7775 6300) $PN 1
J 0
(-7770 6262);
DISPLAY 0.787234 (-7770 6262);
PAINT MONO (-7770 6262);
FORCEPROP 1 LASTPIN (-7775 6100) $PN 2
J 0
(-7770 6110);
DISPLAY 0.787234 (-7770 6110);
PAINT MONO (-7770 6110);
FORCEPROP 1 LAST TOLERANCE 1%
J 0
(-7730 6225);
DISPLAY 0.638298 (-7730 6225);
FORCEPROP 1 LAST VALUE 160K
J 0
(-7730 6275);
DISPLAY 0.638298 (-7730 6275);
FORCEPROP 0 LAST ROOM HSC BOM2
J 0
(-7725 6425);
DISPLAY 0.680851 (-7725 6425);
FORCEPROP 1 LAST WATTAGE 1/16W
J 0
(-7735 6175);
DISPLAY 0.638298 (-7735 6175);
FORCEPROP 1 LAST MATERIAL EMPTY
J 0
(-7735 6125);
DISPLAY 0.638298 (-7735 6125);
FORCEPROP 1 LAST PACK_TYPE 0402LF
J 0
(-7735 6025);
DISPLAY 0.638298 (-7735 6025);
FORCEPROP 2 LAST CDS_LIB pure_quanta
J 0
(-7775 6200);
DISPLAY INVISIBLE (-7775 6200);
FORCEPROP 1 LAST PATH I56
J 0
(-7725 6375);
DISPLAY 0.978723 (-7725 6375);
PAINT WHITE (-7725 6375);
DISPLAY INVISIBLE (-7725 6375);
FORCEPROP 1 LAST PART_NUMBER CS41602FB05
J 0
(-7735 6075);
DISPLAY 0.638298 (-7735 6075);
DISPLAY INVISIBLE (-7735 6075);
FORCEADD Q_RES..2
(-7775 5475);
FORCEPROP 1 LAST LOCATION R6233
J 0
(-7730 5600);
DISPLAY 0.638298 (-7730 5600);
FORCEPROP 0 LAST $SEC 1
J 0
(-7725 5650);
DISPLAY 0.680851 (-7725 5650);
PAINT MONO (-7725 5650);
DISPLAY INVISIBLE (-7725 5650);
FORCEPROP 0 LAST CDS_SEC 1
J 0
(-7725 5650);
DISPLAY 0.680851 (-7725 5650);
DISPLAY INVISIBLE (-7725 5650);
FORCEPROP 1 LASTPIN (-7775 5575) $PN 1
J 0
(-7770 5537);
DISPLAY 0.787234 (-7770 5537);
PAINT MONO (-7770 5537);
FORCEPROP 1 LASTPIN (-7775 5375) $PN 2
J 0
(-7770 5385);
DISPLAY 0.787234 (-7770 5385);
PAINT MONO (-7770 5385);
FORCEPROP 1 LAST PACK_TYPE 0402LF
J 0
(-7735 5300);
DISPLAY 0.638298 (-7735 5300);
FORCEPROP 1 LAST VALUE 10K
J 0
(-7730 5550);
DISPLAY 0.638298 (-7730 5550);
FORCEPROP 1 LAST MATERIAL EMPTY
J 0
(-7735 5400);
DISPLAY 0.638298 (-7735 5400);
FORCEPROP 1 LAST WATTAGE 1/16W
J 0
(-7735 5450);
DISPLAY 0.638298 (-7735 5450);
FORCEPROP 0 LAST ROOM HSC BOM2
J 0
(-7725 5700);
DISPLAY 0.680851 (-7725 5700);
FORCEPROP 1 LAST TOLERANCE 1%
J 0
(-7730 5500);
DISPLAY 0.638298 (-7730 5500);
FORCEPROP 2 LAST CDS_LIB pure_quanta
J 0
(-7775 5475);
DISPLAY INVISIBLE (-7775 5475);
FORCEPROP 1 LAST PATH I57
J 0
(-7725 5650);
DISPLAY 0.978723 (-7725 5650);
PAINT WHITE (-7725 5650);
DISPLAY INVISIBLE (-7725 5650);
FORCEPROP 1 LAST PART_NUMBER CS31002FB08
J 0
(-7735 5350);
DISPLAY 0.638298 (-7735 5350);
DISPLAY INVISIBLE (-7735 5350);
FORCEADD Q_RES..2
(-7300 5425);
FORCEPROP 1 LAST LOCATION R6235
J 0
(-7255 5550);
DISPLAY 0.978723 (-7255 5550);
FORCEPROP 0 LAST $SEC 1
J 0
(-7250 5600);
DISPLAY 0.680851 (-7250 5600);
PAINT MONO (-7250 5600);
DISPLAY INVISIBLE (-7250 5600);
FORCEPROP 0 LAST CDS_SEC 1
J 0
(-7250 5600);
DISPLAY 0.680851 (-7250 5600);
DISPLAY INVISIBLE (-7250 5600);
FORCEPROP 1 LASTPIN (-7300 5525) $PN 1
J 0
(-7295 5487);
DISPLAY 0.787234 (-7295 5487);
PAINT MONO (-7295 5487);
FORCEPROP 1 LASTPIN (-7300 5325) $PN 2
J 0
(-7295 5335);
DISPLAY 0.787234 (-7295 5335);
PAINT MONO (-7295 5335);
FORCEPROP 1 LAST PACK_TYPE 0402LF
J 0
(-7260 5250);
DISPLAY 0.638298 (-7260 5250);
FORCEPROP 1 LAST TOLERANCE 1%
J 0
(-7255 5450);
DISPLAY 0.638298 (-7255 5450);
FORCEPROP 1 LAST WATTAGE 1/16W
J 0
(-7260 5400);
DISPLAY 0.638298 (-7260 5400);
FORCEPROP 1 LAST MATERIAL EMPTY
J 0
(-7260 5350);
DISPLAY 0.638298 (-7260 5350);
FORCEPROP 1 LAST VALUE 10K
J 0
(-7255 5500);
DISPLAY 0.638298 (-7255 5500);
FORCEPROP 0 LAST ROOM HSC BOM2
J 0
(-7250 5650);
DISPLAY 0.680851 (-7250 5650);
FORCEPROP 2 LAST CDS_LIB pure_quanta
J 0
(-7300 5425);
DISPLAY INVISIBLE (-7300 5425);
FORCEPROP 1 LAST PATH I58
J 0
(-7250 5600);
DISPLAY 0.978723 (-7250 5600);
PAINT WHITE (-7250 5600);
DISPLAY INVISIBLE (-7250 5600);
FORCEPROP 1 LAST PART_NUMBER CS31002FB08
J 0
(-7260 5300);
DISPLAY 0.638298 (-7260 5300);
DISPLAY INVISIBLE (-7260 5300);
FORCEADD OFFPAGE..4
R 2
(-8525 6500);
FORCEPROP 2 LAST $XR0 268 
J 0
(-8807 6500);
DISPLAY 0.638298 (-8807 6500);
PAINT MONO (-8807 6500);
FORCEPROP 2 LAST CDS_LIB standard
J 0
(-8525 6500);
DISPLAY INVISIBLE (-8525 6500);
FORCEPROP 1 LAST OFFPAGE TRUE
J 2
(-8850 6375);
DISPLAY 0.872340 (-8850 6375);
PAINT GREEN (-8850 6375);
DISPLAY INVISIBLE (-8850 6375);
FORCEPROP 1 LAST COMMENT_BODY TRUE
J 2
(-8500 6400);
DISPLAY 0.872340 (-8500 6400);
PAINT GREEN (-8500 6400);
DISPLAY INVISIBLE (-8500 6400);
FORCEPROP 2 LAST PATH I59
J 0
(-8475 6575);
DISPLAY 0.680851 (-8475 6575);
DISPLAY INVISIBLE (-8475 6575);
FORCEADD Q_CAP..1
(-4750 2450);
FORCEPROP 1 LAST LOCATION C1787
J 0
(-4700 2550);
DISPLAY 0.702128 (-4700 2550);
FORCEPROP 0 LAST $SEC 1
J 0
(-4700 2600);
DISPLAY 0.680851 (-4700 2600);
PAINT MONO (-4700 2600);
DISPLAY INVISIBLE (-4700 2600);
FORCEPROP 0 LAST CDS_SEC 1
J 0
(-4700 2600);
DISPLAY 1.021277 (-4700 2600);
DISPLAY INVISIBLE (-4700 2600);
FORCEPROP 1 LASTPIN (-4750 2550) $PN 1
J 0
(-4740 2530);
DISPLAY 0.808511 (-4740 2530);
PAINT WHITE (-4740 2530);
FORCEPROP 1 LASTPIN (-4750 2350) $PN 2
J 0
(-4740 2330);
DISPLAY 0.808511 (-4740 2330);
PAINT WHITE (-4740 2330);
FORCEPROP 1 LAST VOLTAGE 16V
J 0
(-4700 2450);
DISPLAY 0.510638 (-4700 2450);
FORCEPROP 1 LAST TOLERANCE 10%
J 0
(-4700 2400);
DISPLAY 0.510638 (-4700 2400);
FORCEPROP 1 LAST MATERIAL X7R
J 0
(-4700 2350);
DISPLAY 0.510638 (-4700 2350);
FORCEPROP 1 LAST PACK_TYPE C0402
J 0
(-4700 2250);
DISPLAY 0.510638 (-4700 2250);
FORCEPROP 0 LAST ROOM HSC BOM2
J 0
(-4700 2600);
DISPLAY 0.680851 (-4700 2600);
FORCEPROP 1 LAST VALUE 0.1UF
J 0
(-4700 2500);
DISPLAY 0.510638 (-4700 2500);
FORCEPROP 2 LAST CDS_LIB pure_quanta
J 0
(-4750 2450);
DISPLAY INVISIBLE (-4750 2450);
FORCEPROP 1 LAST PATH I6
J 0
(-4700 2600);
DISPLAY 0.978723 (-4700 2600);
PAINT WHITE (-4700 2600);
DISPLAY INVISIBLE (-4700 2600);
FORCEPROP 1 LAST PART_NUMBER CH4103K1B08
J 0
(-4700 2300);
DISPLAY 0.510638 (-4700 2300);
DISPLAY INVISIBLE (-4700 2300);
FORCEADD GND..1
(-7775 5000);
FORCEPROP 3 LASTPIN (-7775 5050) SIG_NAME GND\g
J 0
(-7765 5060);
DISPLAY 0.659574 (-7765 5060);
PAINT MONO (-7765 5060);
DISPLAY INVISIBLE (-7765 5060);
FORCEPROP 2 LAST CDS_LIB pure_quanta_power
J 0
(-7775 5000);
DISPLAY INVISIBLE (-7775 5000);
FORCEPROP 1 LAST SIZE 1B
J 0
(-7700 4950);
DISPLAY 0.872340 (-7700 4950);
PAINT AQUA (-7700 4950);
DISPLAY INVISIBLE (-7700 4950);
FORCEPROP 2 LAST ROOM VR_DDR1_POWER_STAGE
J 0
(-8000 5075);
DISPLAY INVISIBLE (-8000 5075);
FORCEPROP 1 LAST HDL_POWER GND
J 0
(-7775 5150);
DISPLAY 1.170213 (-7775 5150);
PAINT GREEN (-7775 5150);
DISPLAY INVISIBLE (-7775 5150);
FORCEPROP 1 LAST PATH I60
J 0
(-7700 5000);
DISPLAY 0.872340 (-7700 5000);
PAINT AQUA (-7700 5000);
DISPLAY INVISIBLE (-7700 5000);
FORCEADD GND..1
(-5025 5400);
FORCEPROP 3 LASTPIN (-5025 5450) SIG_NAME GND\g
J 0
(-5015 5460);
DISPLAY 0.659574 (-5015 5460);
PAINT MONO (-5015 5460);
DISPLAY INVISIBLE (-5015 5460);
FORCEPROP 2 LAST ROOM VR_DDR1_POWER_STAGE
J 0
(-5250 5475);
DISPLAY INVISIBLE (-5250 5475);
FORCEPROP 1 LAST SIZE 1B
J 0
(-4950 5350);
DISPLAY 0.872340 (-4950 5350);
PAINT AQUA (-4950 5350);
DISPLAY INVISIBLE (-4950 5350);
FORCEPROP 2 LAST CDS_LIB pure_quanta_power
J 0
(-5025 5400);
DISPLAY INVISIBLE (-5025 5400);
FORCEPROP 1 LAST HDL_POWER GND
J 0
(-5025 5550);
DISPLAY 1.170213 (-5025 5550);
PAINT GREEN (-5025 5550);
DISPLAY INVISIBLE (-5025 5550);
FORCEPROP 1 LAST PATH I61
J 0
(-4950 5400);
DISPLAY 0.872340 (-4950 5400);
PAINT AQUA (-4950 5400);
DISPLAY INVISIBLE (-4950 5400);
FORCEADD Q_RES..2
(-4450 6225);
FORCEPROP 1 LAST LOCATION R6236
J 0
(-4405 6350);
DISPLAY 0.978723 (-4405 6350);
FORCEPROP 0 LAST $SEC 1
J 0
(-4400 6400);
DISPLAY 0.680851 (-4400 6400);
PAINT MONO (-4400 6400);
DISPLAY INVISIBLE (-4400 6400);
FORCEPROP 0 LAST CDS_SEC 1
J 0
(-4400 6400);
DISPLAY 0.680851 (-4400 6400);
DISPLAY INVISIBLE (-4400 6400);
FORCEPROP 1 LASTPIN (-4450 6325) $PN 1
J 0
(-4445 6287);
DISPLAY 0.787234 (-4445 6287);
PAINT MONO (-4445 6287);
FORCEPROP 1 LASTPIN (-4450 6125) $PN 2
J 0
(-4445 6135);
DISPLAY 0.787234 (-4445 6135);
PAINT MONO (-4445 6135);
FORCEPROP 1 LAST PACK_TYPE 0402LF
J 0
(-4410 6050);
DISPLAY 0.638298 (-4410 6050);
FORCEPROP 1 LAST MATERIAL EMPTY
J 0
(-4410 6150);
DISPLAY 0.638298 (-4410 6150);
FORCEPROP 1 LAST TOLERANCE 1%
J 0
(-4405 6250);
DISPLAY 0.638298 (-4405 6250);
FORCEPROP 1 LAST VALUE 10K
J 0
(-4405 6300);
DISPLAY 0.638298 (-4405 6300);
FORCEPROP 0 LAST ROOM HSC BOM2
J 0
(-4400 6450);
DISPLAY 0.680851 (-4400 6450);
FORCEPROP 1 LAST WATTAGE 1/16W
J 0
(-4410 6200);
DISPLAY 0.638298 (-4410 6200);
FORCEPROP 2 LAST CDS_LIB pure_quanta
J 0
(-4450 6225);
DISPLAY INVISIBLE (-4450 6225);
FORCEPROP 1 LAST PATH I63
J 0
(-4400 6400);
DISPLAY 0.978723 (-4400 6400);
PAINT WHITE (-4400 6400);
DISPLAY INVISIBLE (-4400 6400);
FORCEPROP 1 LAST PART_NUMBER CS31002FB08
J 0
(-4410 6100);
DISPLAY 0.638298 (-4410 6100);
DISPLAY INVISIBLE (-4410 6100);
FORCEADD UNIVERSAL_POWER..1
(-4450 6525);
FORCEPROP 3 LASTPIN (-4450 6475) SIG_NAME P3V3_AUX\g
J 0
(-4440 6485);
DISPLAY 0.659574 (-4440 6485);
PAINT MONO (-4440 6485);
DISPLAY INVISIBLE (-4440 6485);
FORCEPROP 1 LAST HDL_POWER P3V3_AUX
J 1
(-4450 6575);
DISPLAY 0.723404 (-4450 6575);
PAINT GREEN (-4450 6575);
FORCEPROP 2 LAST CDS_LIB pure_quanta_power
J 0
(-4450 6525);
DISPLAY INVISIBLE (-4450 6525);
FORCEPROP 1 LAST PATH I64
J 0
(-4400 6550);
DISPLAY 0.872340 (-4400 6550);
PAINT AQUA (-4400 6550);
DISPLAY INVISIBLE (-4400 6550);
FORCEADD OFFPAGE..2
(-1600 5750);
FORCEPROP 2 LAST $XR1 80 
J 0
(-1291 5750);
DISPLAY 0.638298 (-1291 5750);
PAINT MONO (-1291 5750);
FORCEPROP 2 LAST $XR0 263 
J 0
(-1411 5750);
DISPLAY 0.638298 (-1411 5750);
PAINT MONO (-1411 5750);
FORCEPROP 2 LAST CDS_LIB standard
J 0
(-1600 5750);
DISPLAY INVISIBLE (-1600 5750);
FORCEPROP 1 LAST OFFPAGE TRUE
J 0
(-1275 5625);
DISPLAY 0.872340 (-1275 5625);
PAINT AQUA (-1275 5625);
DISPLAY INVISIBLE (-1275 5625);
FORCEPROP 1 LAST COMMENT_BODY TRUE
J 0
(-1645 5655);
DISPLAY 0.872340 (-1645 5655);
PAINT GREEN (-1645 5655);
DISPLAY INVISIBLE (-1645 5655);
FORCEPROP 2 LAST PATH I65
J 0
(-1425 5825);
DISPLAY 0.680851 (-1425 5825);
DISPLAY INVISIBLE (-1425 5825);
FORCEADD Q_RES..2
(-4450 5525);
FORCEPROP 1 LAST LOCATION R6237
J 0
(-4400 5650);
DISPLAY 0.787234 (-4400 5650);
FORCEPROP 0 LAST $SEC 1
J 0
(-4400 5700);
DISPLAY 0.680851 (-4400 5700);
PAINT MONO (-4400 5700);
DISPLAY INVISIBLE (-4400 5700);
FORCEPROP 0 LAST CDS_SEC 1
J 0
(-4400 5700);
DISPLAY 0.680851 (-4400 5700);
DISPLAY INVISIBLE (-4400 5700);
FORCEPROP 1 LASTPIN (-4450 5625) $PN 1
J 0
(-4445 5587);
DISPLAY 0.787234 (-4445 5587);
PAINT MONO (-4445 5587);
FORCEPROP 1 LASTPIN (-4450 5425) $PN 2
J 0
(-4445 5435);
DISPLAY 0.787234 (-4445 5435);
PAINT MONO (-4445 5435);
FORCEPROP 1 LAST MATERIAL EMPTY
J 0
(-4410 5450);
DISPLAY 0.787234 (-4410 5450);
FORCEPROP 1 LAST VALUE 0
J 0
(-4405 5600);
DISPLAY 0.787234 (-4405 5600);
FORCEPROP 1 LAST PACK_TYPE 0402LF
J 0
(-4410 5350);
DISPLAY 0.787234 (-4410 5350);
FORCEPROP 0 LAST ROOM HSC BOM2
J 0
(-4400 5300);
DISPLAY 0.680851 (-4400 5300);
FORCEPROP 1 LAST TOLERANCE 5%
J 0
(-4405 5550);
DISPLAY 0.787234 (-4405 5550);
FORCEPROP 1 LAST WATTAGE 1/16W
J 0
(-4410 5500);
DISPLAY 0.787234 (-4410 5500);
FORCEPROP 2 LAST CDS_LIB pure_quanta
J 0
(-4450 5525);
DISPLAY INVISIBLE (-4450 5525);
FORCEPROP 1 LAST PATH I66
J 0
(-4400 5700);
DISPLAY 0.978723 (-4400 5700);
PAINT WHITE (-4400 5700);
DISPLAY INVISIBLE (-4400 5700);
FORCEPROP 1 LAST PART_NUMBER CS00002JB13
J 0
(-4410 5400);
DISPLAY 0.787234 (-4410 5400);
DISPLAY INVISIBLE (-4410 5400);
FORCEADD GND..1
(-4450 5200);
FORCEPROP 3 LASTPIN (-4450 5250) SIG_NAME GND\g
J 0
(-4440 5260);
DISPLAY 0.659574 (-4440 5260);
PAINT MONO (-4440 5260);
DISPLAY INVISIBLE (-4440 5260);
FORCEPROP 2 LAST CDS_LIB pure_quanta_power
J 0
(-4450 5200);
DISPLAY INVISIBLE (-4450 5200);
FORCEPROP 1 LAST SIZE 1B
J 0
(-4375 5150);
DISPLAY 0.872340 (-4375 5150);
PAINT AQUA (-4375 5150);
DISPLAY INVISIBLE (-4375 5150);
FORCEPROP 2 LAST ROOM VR_DDR1_POWER_STAGE
J 0
(-4675 5275);
DISPLAY INVISIBLE (-4675 5275);
FORCEPROP 1 LAST HDL_POWER GND
J 0
(-4450 5350);
DISPLAY 1.170213 (-4450 5350);
PAINT GREEN (-4450 5350);
DISPLAY INVISIBLE (-4450 5350);
FORCEPROP 1 LAST PATH I67
J 0
(-4375 5200);
DISPLAY 0.872340 (-4375 5200);
PAINT AQUA (-4375 5200);
DISPLAY INVISIBLE (-4375 5200);
FORCEADD MOSFET_NCH_GDS_ESD_PROTECTED..1
(-3450 6275);
FORCEPROP 1 LAST LOCATION U6004
J 0
(-3308 6239);
DISPLAY 0.723404 (-3308 6239);
PAINT GREEN (-3308 6239);
FORCEPROP 0 LAST $SEC 1
J 0
(-3300 6375);
DISPLAY 0.680851 (-3300 6375);
PAINT MONO (-3300 6375);
DISPLAY INVISIBLE (-3300 6375);
FORCEPROP 0 LAST CDS_SEC 1
J 0
(-3300 6375);
DISPLAY 0.680851 (-3300 6375);
DISPLAY INVISIBLE (-3300 6375);
FORCEPROP 0 LASTPIN (-3425 6475) $PN D
R 1
J 0
(-3435 6485);
DISPLAY 0.680851 (-3435 6485);
PAINT MONO (-3435 6485);
FORCEPROP 0 LASTPIN (-3625 6275) $PN G
J 2
(-3635 6285);
DISPLAY 0.680851 (-3635 6285);
PAINT MONO (-3635 6285);
FORCEPROP 0 LASTPIN (-3425 6075) $PN S
R 1
J 2
(-3435 6065);
DISPLAY 0.680851 (-3435 6065);
PAINT MONO (-3435 6065);
FORCEPROP 2 LAST VALUE 2N7002K
J 0
(-3300 6275);
DISPLAY 0.680851 (-3300 6275);
FORCEPROP 1 LAST MATERIAL EMPTY
J 0
(-3308 6130);
DISPLAY 0.723404 (-3308 6130);
PAINT GREEN (-3308 6130);
FORCEPROP 2 LAST PART_TYPE SMLF
J 0
(-3300 6325);
DISPLAY 0.680851 (-3300 6325);
FORCEPROP 0 LAST ROOM HSC BOM2
J 0
(-3300 6425);
DISPLAY 0.680851 (-3300 6425);
FORCEPROP 2 LAST CDS_LIB pure_quanta
J 0
(-3450 6275);
DISPLAY INVISIBLE (-3450 6275);
FORCEPROP 1 LAST NEEDS_NO_SIZE TRUE
J 0
(-3325 6165);
DISPLAY 0.723404 (-3325 6165);
PAINT GREEN (-3325 6165);
DISPLAY INVISIBLE (-3325 6165);
FORCEPROP 1 LAST CDS_LMAN_SYM_OUTLINE -125,150,125,-150
J 0
(-3450 6275);
DISPLAY 0.468085 (-3450 6275);
PAINT GREEN (-3450 6275);
DISPLAY INVISIBLE (-3450 6275);
FORCEPROP 1 LAST PATH I68
J 0
(-3325 6125);
DISPLAY 0.723404 (-3325 6125);
PAINT GREEN (-3325 6125);
DISPLAY INVISIBLE (-3325 6125);
FORCEPROP 1 LAST PART_NUMBER BAM70020002
J 0
(-3308 6187);
DISPLAY 0.723404 (-3308 6187);
PAINT GREEN (-3308 6187);
DISPLAY INVISIBLE (-3308 6187);
FORCEADD GND..1
(-3425 5900);
FORCEPROP 3 LASTPIN (-3425 5950) SIG_NAME GND\g
J 0
(-3415 5960);
DISPLAY 0.659574 (-3415 5960);
PAINT MONO (-3415 5960);
DISPLAY INVISIBLE (-3415 5960);
FORCEPROP 1 LAST SIZE 1B
J 0
(-3350 5850);
DISPLAY 0.872340 (-3350 5850);
PAINT AQUA (-3350 5850);
DISPLAY INVISIBLE (-3350 5850);
FORCEPROP 2 LAST ROOM VR_DDR1_POWER_STAGE
J 0
(-3650 5975);
DISPLAY INVISIBLE (-3650 5975);
FORCEPROP 2 LAST CDS_LIB pure_quanta_power
J 0
(-3425 5900);
DISPLAY INVISIBLE (-3425 5900);
FORCEPROP 1 LAST HDL_POWER GND
J 0
(-3425 6050);
DISPLAY 1.170213 (-3425 6050);
PAINT GREEN (-3425 6050);
DISPLAY INVISIBLE (-3425 6050);
FORCEPROP 1 LAST PATH I69
J 0
(-3350 5900);
DISPLAY 0.872340 (-3350 5900);
PAINT AQUA (-3350 5900);
DISPLAY INVISIBLE (-3350 5900);
FORCEADD UNIVERSAL_POWER..1
(-4575 2850);
FORCEPROP 3 LASTPIN (-4575 2800) SIG_NAME P3V3_AUX\g
J 0
(-4565 2810);
DISPLAY 0.659574 (-4565 2810);
PAINT MONO (-4565 2810);
DISPLAY INVISIBLE (-4565 2810);
FORCEPROP 1 LAST HDL_POWER P3V3_AUX
J 1
(-4575 2900);
DISPLAY 0.702128 (-4575 2900);
PAINT GREEN (-4575 2900);
FORCEPROP 2 LAST CDS_LIB pure_quanta_power
J 0
(-4575 2850);
DISPLAY INVISIBLE (-4575 2850);
FORCEPROP 1 LAST PATH I7
J 0
(-4525 2875);
DISPLAY 0.872340 (-4525 2875);
PAINT AQUA (-4525 2875);
DISPLAY INVISIBLE (-4525 2875);
FORCEADD Q_RES..2
(-2300 6175);
FORCEPROP 1 LAST LOCATION R6239
J 0
(-2255 6300);
DISPLAY 0.638298 (-2255 6300);
FORCEPROP 0 LAST $SEC 1
J 0
(-2250 6350);
DISPLAY 0.680851 (-2250 6350);
PAINT MONO (-2250 6350);
DISPLAY INVISIBLE (-2250 6350);
FORCEPROP 0 LAST CDS_SEC 1
J 0
(-2250 6350);
DISPLAY 0.680851 (-2250 6350);
DISPLAY INVISIBLE (-2250 6350);
FORCEPROP 1 LASTPIN (-2300 6275) $PN 1
J 0
(-2295 6237);
DISPLAY 0.787234 (-2295 6237);
PAINT MONO (-2295 6237);
FORCEPROP 1 LASTPIN (-2300 6075) $PN 2
J 0
(-2295 6085);
DISPLAY 0.787234 (-2295 6085);
PAINT MONO (-2295 6085);
FORCEPROP 0 LAST ROOM HSC BOM2
J 0
(-2250 6400);
DISPLAY 0.680851 (-2250 6400);
FORCEPROP 1 LAST WATTAGE 1/16W
J 0
(-2260 6150);
DISPLAY 0.638298 (-2260 6150);
FORCEPROP 1 LAST MATERIAL CHIP
J 0
(-2260 6100);
DISPLAY 0.638298 (-2260 6100);
FORCEPROP 1 LAST PACK_TYPE 0402LF
J 0
(-2260 6000);
DISPLAY 0.638298 (-2260 6000);
FORCEPROP 1 LAST TOLERANCE 1%
J 0
(-2255 6200);
DISPLAY 0.638298 (-2255 6200);
FORCEPROP 1 LAST VALUE 10K
J 0
(-2255 6250);
DISPLAY 0.638298 (-2255 6250);
FORCEPROP 2 LAST CDS_LIB pure_quanta
J 0
(-2300 6175);
DISPLAY INVISIBLE (-2300 6175);
FORCEPROP 1 LAST PATH I70
J 0
(-2250 6350);
DISPLAY 0.978723 (-2250 6350);
PAINT WHITE (-2250 6350);
DISPLAY INVISIBLE (-2250 6350);
FORCEPROP 1 LAST PART_NUMBER CS31002FB08
J 0
(-2260 6050);
DISPLAY 0.638298 (-2260 6050);
DISPLAY INVISIBLE (-2260 6050);
FORCEADD UNIVERSAL_POWER..1
(-2300 6550);
FORCEPROP 3 LASTPIN (-2300 6500) SIG_NAME P3V3_AUX\g
J 0
(-2290 6510);
DISPLAY 0.659574 (-2290 6510);
PAINT MONO (-2290 6510);
DISPLAY INVISIBLE (-2290 6510);
FORCEPROP 1 LAST HDL_POWER P3V3_AUX
J 1
(-2300 6600);
DISPLAY 0.723404 (-2300 6600);
PAINT GREEN (-2300 6600);
FORCEPROP 2 LAST CDS_LIB pure_quanta_power
J 0
(-2300 6550);
DISPLAY INVISIBLE (-2300 6550);
FORCEPROP 1 LAST PATH I71
J 0
(-2250 6575);
DISPLAY 0.872340 (-2250 6575);
PAINT AQUA (-2250 6575);
DISPLAY INVISIBLE (-2250 6575);
FORCEADD Q_RES..2
(-2775 6225);
FORCEPROP 1 LAST LOCATION R6238
J 0
(-2730 6350);
DISPLAY 0.787234 (-2730 6350);
FORCEPROP 0 LAST $SEC 1
J 0
(-2725 6400);
DISPLAY 0.680851 (-2725 6400);
PAINT MONO (-2725 6400);
DISPLAY INVISIBLE (-2725 6400);
FORCEPROP 0 LAST CDS_SEC 1
J 0
(-2725 6400);
DISPLAY 0.680851 (-2725 6400);
DISPLAY INVISIBLE (-2725 6400);
FORCEPROP 1 LASTPIN (-2775 6325) $PN 1
J 0
(-2770 6287);
DISPLAY 0.787234 (-2770 6287);
PAINT MONO (-2770 6287);
FORCEPROP 1 LASTPIN (-2775 6125) $PN 2
J 0
(-2770 6135);
DISPLAY 0.787234 (-2770 6135);
PAINT MONO (-2770 6135);
FORCEPROP 1 LAST PACK_TYPE 0402LF
J 0
(-2735 6050);
DISPLAY 0.638298 (-2735 6050);
FORCEPROP 0 LAST ROOM HSC BOM2
J 0
(-2725 6450);
DISPLAY 0.680851 (-2725 6450);
FORCEPROP 1 LAST MATERIAL EMPTY
J 0
(-2735 6150);
DISPLAY 0.638298 (-2735 6150);
FORCEPROP 1 LAST WATTAGE 1/16W
J 0
(-2735 6200);
DISPLAY 0.638298 (-2735 6200);
FORCEPROP 1 LAST TOLERANCE 5%
J 0
(-2730 6250);
DISPLAY 0.638298 (-2730 6250);
FORCEPROP 1 LAST VALUE 0
J 0
(-2730 6300);
DISPLAY 0.638298 (-2730 6300);
FORCEPROP 2 LAST CDS_LIB pure_quanta
J 0
(-2775 6225);
DISPLAY INVISIBLE (-2775 6225);
FORCEPROP 1 LAST PATH I72
J 0
(-2725 6400);
DISPLAY 0.978723 (-2725 6400);
PAINT WHITE (-2725 6400);
DISPLAY INVISIBLE (-2725 6400);
FORCEPROP 1 LAST PART_NUMBER CS00002JB13
J 0
(-2735 6100);
DISPLAY 0.638298 (-2735 6100);
DISPLAY INVISIBLE (-2735 6100);
FORCEADD Q_RES..1
(-5275 4925);
FORCEPROP 1 LAST LOCATION R6210
J 0
(-5675 4925);
DISPLAY 1.085106 (-5675 4925);
FORCEPROP 0 LAST $SEC 1
J 0
(-5475 4975);
DISPLAY 0.680851 (-5475 4975);
PAINT MONO (-5475 4975);
DISPLAY INVISIBLE (-5475 4975);
FORCEPROP 0 LAST CDS_SEC 1
J 0
(-5475 4975);
DISPLAY 0.680851 (-5475 4975);
DISPLAY INVISIBLE (-5475 4975);
FORCEPROP 1 LASTPIN (-5375 4925) $PN 1
J 0
(-5363 4937);
DISPLAY 1.021277 (-5363 4937);
PAINT MONO (-5363 4937);
FORCEPROP 1 LASTPIN (-5175 4925) $PN 2
J 0
(-5213 4937);
DISPLAY 1.021277 (-5213 4937);
PAINT MONO (-5213 4937);
FORCEPROP 1 LAST TOLERANCE 5%
J 0
(-4950 4850);
DISPLAY 1.276596 (-4950 4850);
FORCEPROP 0 LAST ROOM HSC BOM2
J 0
(-5375 5125);
DISPLAY 0.680851 (-5375 5125);
FORCEPROP 1 LAST MATERIAL CHIP
J 0
(-5375 5000);
DISPLAY 1.276596 (-5375 5000);
FORCEPROP 1 LAST PACK_TYPE 0402LF
J 0
(-5650 4850);
DISPLAY 1.021277 (-5650 4850);
FORCEPROP 1 LAST VALUE 0
J 2
(-5025 4925);
DISPLAY 1.276596 (-5025 4925);
FORCEPROP 1 LAST WATTAGE 1/16W
J 2
(-5050 4850);
DISPLAY 1.021277 (-5050 4850);
FORCEPROP 2 LAST CDS_LIB pure_quanta
J 0
(-5275 4925);
DISPLAY INVISIBLE (-5275 4925);
FORCEPROP 1 LAST PATH I73
J 0
(-5325 5075);
DISPLAY 0.978723 (-5325 5075);
PAINT WHITE (-5325 5075);
DISPLAY INVISIBLE (-5325 5075);
FORCEPROP 1 LAST PART_NUMBER CS00002JB13
J 0
(-5475 4800);
DISPLAY 1.021277 (-5475 4800);
DISPLAY INVISIBLE (-5475 4800);
FORCEADD Q_RES..1
(-3500 1250);
FORCEPROP 1 LAST LOCATION R353
J 0
(-3700 1250);
DISPLAY 0.553191 (-3700 1250);
FORCEPROP 0 LAST $SEC 1
J 0
(-3625 1325);
DISPLAY 0.680851 (-3625 1325);
PAINT MONO (-3625 1325);
DISPLAY INVISIBLE (-3625 1325);
FORCEPROP 0 LAST CDS_SEC 1
J 0
(-3625 1325);
DISPLAY 0.680851 (-3625 1325);
DISPLAY INVISIBLE (-3625 1325);
FORCEPROP 1 LASTPIN (-3600 1250) $PN 1
J 0
(-3588 1262);
DISPLAY 0.787234 (-3588 1262);
PAINT MONO (-3588 1262);
FORCEPROP 1 LASTPIN (-3400 1250) $PN 2
J 0
(-3438 1262);
DISPLAY 0.787234 (-3438 1262);
PAINT MONO (-3438 1262);
FORCEPROP 1 LAST MATERIAL CHIP
J 0
(-3275 1250);
DISPLAY 0.404255 (-3275 1250);
FORCEPROP 1 LAST VALUE 0
J 2
(-3350 1250);
DISPLAY 0.404255 (-3350 1250);
FORCEPROP 1 LAST TOLERANCE 5%
J 0
(-3325 1250);
DISPLAY 0.404255 (-3325 1250);
FORCEPROP 1 LAST WATTAGE 1/16W
J 2
(-3375 1225);
DISPLAY 0.319149 (-3375 1225);
FORCEPROP 1 LAST PACK_TYPE 0402LF
J 0
(-3625 1225);
DISPLAY 0.319149 (-3625 1225);
FORCEPROP 0 LAST ROOM HSC BOM2
J 0
(-3675 1325);
DISPLAY 0.680851 (-3675 1325);
FORCEPROP 2 LAST CDS_LIB pure_quanta
J 0
(-3500 1250);
DISPLAY INVISIBLE (-3500 1250);
FORCEPROP 1 LAST PATH I74
J 0
(-3550 1400);
DISPLAY 0.978723 (-3550 1400);
PAINT WHITE (-3550 1400);
DISPLAY INVISIBLE (-3550 1400);
FORCEPROP 1 LAST PART_NUMBER CS00002JB13
J 0
(-3625 1200);
DISPLAY 0.319149 (-3625 1200);
DISPLAY INVISIBLE (-3625 1200);
FORCEADD OFFPAGE..5
R 2
(-1900 1250);
FORCEPROP 2 LAST $XR0 82 
J 0
(-1711 1250);
DISPLAY 0.638298 (-1711 1250);
PAINT MONO (-1711 1250);
FORCEPROP 2 LAST CDS_LIB standard
J 0
(-1900 1250);
DISPLAY INVISIBLE (-1900 1250);
FORCEPROP 1 LAST OFFPAGE TRUE
J 2
(-2225 1125);
DISPLAY 0.872340 (-2225 1125);
PAINT GREEN (-2225 1125);
DISPLAY INVISIBLE (-2225 1125);
FORCEPROP 1 LAST COMMENT_BODY TRUE
J 2
(-2000 1175);
DISPLAY 0.872340 (-2000 1175);
PAINT PEACH (-2000 1175);
DISPLAY INVISIBLE (-2000 1175);
FORCEPROP 2 LAST PATH I75
J 0
(-1725 1325);
DISPLAY 0.680851 (-1725 1325);
DISPLAY INVISIBLE (-1725 1325);
FORCEADD Q_RES..2
(-2275 1600);
FORCEPROP 1 LAST LOCATION R354
J 0
(-2230 1725);
DISPLAY 0.638298 (-2230 1725);
FORCEPROP 0 LAST $SEC 1
J 0
(-2225 1775);
DISPLAY 0.680851 (-2225 1775);
PAINT MONO (-2225 1775);
DISPLAY INVISIBLE (-2225 1775);
FORCEPROP 0 LAST CDS_SEC 1
J 0
(-2225 1775);
DISPLAY 0.680851 (-2225 1775);
DISPLAY INVISIBLE (-2225 1775);
FORCEPROP 1 LASTPIN (-2275 1700) $PN 1
J 0
(-2270 1662);
DISPLAY 0.787234 (-2270 1662);
PAINT MONO (-2270 1662);
FORCEPROP 1 LASTPIN (-2275 1500) $PN 2
J 0
(-2270 1510);
DISPLAY 0.787234 (-2270 1510);
PAINT MONO (-2270 1510);
FORCEPROP 1 LAST PACK_TYPE 0402LF
J 0
(-2235 1425);
DISPLAY 0.638298 (-2235 1425);
FORCEPROP 1 LAST TOLERANCE 1%
J 0
(-2230 1625);
DISPLAY 0.638298 (-2230 1625);
FORCEPROP 1 LAST WATTAGE 1/16W
J 0
(-2235 1575);
DISPLAY 0.638298 (-2235 1575);
FORCEPROP 1 LAST MATERIAL CHIP
J 0
(-2235 1525);
DISPLAY 0.638298 (-2235 1525);
FORCEPROP 0 LAST ROOM HSC BOM2
J 0
(-2225 1825);
DISPLAY 0.680851 (-2225 1825);
FORCEPROP 1 LAST VALUE 10.5K
J 0
(-2230 1675);
DISPLAY 0.638298 (-2230 1675);
FORCEPROP 2 LAST CDS_LIB pure_quanta
J 0
(-2275 1600);
DISPLAY INVISIBLE (-2275 1600);
FORCEPROP 1 LAST PATH I76
J 0
(-2225 1775);
DISPLAY 0.978723 (-2225 1775);
PAINT WHITE (-2225 1775);
DISPLAY INVISIBLE (-2225 1775);
FORCEPROP 1 LAST PART_NUMBER CS31052FB03
J 0
(-2235 1475);
DISPLAY 0.638298 (-2235 1475);
DISPLAY INVISIBLE (-2235 1475);
FORCEADD UNIVERSAL_POWER..1
(-2275 1850);
FORCEPROP 3 LASTPIN (-2275 1800) SIG_NAME P3V3_AUX\g
J 0
(-2265 1810);
DISPLAY 0.659574 (-2265 1810);
PAINT MONO (-2265 1810);
DISPLAY INVISIBLE (-2265 1810);
FORCEPROP 1 LAST HDL_POWER P3V3_AUX
J 1
(-2275 1900);
DISPLAY 0.723404 (-2275 1900);
PAINT GREEN (-2275 1900);
FORCEPROP 2 LAST CDS_LIB pure_quanta_power
J 0
(-2275 1850);
DISPLAY INVISIBLE (-2275 1850);
FORCEPROP 1 LAST PATH I77
J 0
(-2225 1875);
DISPLAY 0.872340 (-2225 1875);
PAINT AQUA (-2225 1875);
DISPLAY INVISIBLE (-2225 1875);
FORCEADD UNIVERSAL_POWER..1
(-2125 2875);
FORCEPROP 3 LASTPIN (-2125 2825) SIG_NAME P3V3_AUX\g
J 0
(-2115 2835);
DISPLAY 0.659574 (-2115 2835);
PAINT MONO (-2115 2835);
DISPLAY INVISIBLE (-2115 2835);
FORCEPROP 1 LAST HDL_POWER P3V3_AUX
J 1
(-2125 2925);
DISPLAY 0.723404 (-2125 2925);
PAINT GREEN (-2125 2925);
FORCEPROP 2 LAST CDS_LIB pure_quanta_power
J 0
(-2125 2875);
DISPLAY INVISIBLE (-2125 2875);
FORCEPROP 1 LAST PATH I78
J 0
(-2075 2900);
DISPLAY 0.872340 (-2075 2900);
PAINT AQUA (-2075 2900);
DISPLAY INVISIBLE (-2075 2900);
FORCEADD Q_RES..2
R 2
(-2125 2600);
FORCEPROP 1 LAST LOCATION R355
J 2
(-2170 2725);
DISPLAY 0.978723 (-2170 2725);
FORCEPROP 0 LAST $SEC 1
J 0
(-2150 2775);
DISPLAY 0.680851 (-2150 2775);
PAINT MONO (-2150 2775);
DISPLAY INVISIBLE (-2150 2775);
FORCEPROP 0 LAST CDS_SEC 1
J 0
(-2150 2775);
DISPLAY 0.680851 (-2150 2775);
DISPLAY INVISIBLE (-2150 2775);
FORCEPROP 1 LASTPIN (-2125 2700) $PN 1
J 2
(-2130 2662);
DISPLAY 0.787234 (-2130 2662);
PAINT MONO (-2130 2662);
FORCEPROP 1 LASTPIN (-2125 2500) $PN 2
J 2
(-2130 2510);
DISPLAY 0.787234 (-2130 2510);
PAINT MONO (-2130 2510);
FORCEPROP 1 LAST VALUE 10.5K
J 2
(-2170 2675);
DISPLAY 0.638298 (-2170 2675);
FORCEPROP 0 LAST ROOM HSC BOM2
J 0
(-2425 2800);
DISPLAY 0.680851 (-2425 2800);
FORCEPROP 1 LAST TOLERANCE 1%
J 2
(-2170 2625);
DISPLAY 0.638298 (-2170 2625);
FORCEPROP 1 LAST WATTAGE 1/16W
J 2
(-2165 2575);
DISPLAY 0.638298 (-2165 2575);
FORCEPROP 1 LAST PACK_TYPE 0402LF
J 2
(-2165 2425);
DISPLAY 0.638298 (-2165 2425);
FORCEPROP 1 LAST MATERIAL CHIP
J 2
(-2165 2525);
DISPLAY 0.638298 (-2165 2525);
FORCEPROP 2 LAST CDS_LIB pure_quanta
J 2
(-2125 2600);
DISPLAY INVISIBLE (-2125 2600);
FORCEPROP 1 LAST PATH I79
J 2
(-2175 2775);
DISPLAY 0.978723 (-2175 2775);
PAINT WHITE (-2175 2775);
DISPLAY INVISIBLE (-2175 2775);
FORCEPROP 1 LAST PART_NUMBER CS31052FB03
J 2
(-2165 2475);
DISPLAY 0.638298 (-2165 2475);
DISPLAY INVISIBLE (-2165 2475);
FORCEADD NCT7718W..1
(-3825 2075);
FORCEPROP 1 LAST LOCATION U143
J 0
(-4075 2475);
DISPLAY 0.723404 (-4075 2475);
PAINT GREEN (-4075 2475);
FORCEPROP 0 LAST $SEC 1
J 0
(-4050 2600);
DISPLAY 0.680851 (-4050 2600);
PAINT MONO (-4050 2600);
DISPLAY INVISIBLE (-4050 2600);
FORCEPROP 0 LAST CDS_SEC 1
J 0
(-4025 2625);
DISPLAY 1.021277 (-4025 2625);
DISPLAY INVISIBLE (-4025 2625);
FORCEPROP 0 LASTPIN (-3425 2025) $PN 6
J 0
(-3415 2035);
DISPLAY 0.680851 (-3415 2035);
PAINT MONO (-3415 2035);
FORCEPROP 0 LASTPIN (-4225 2125) $PN 2
J 2
(-4235 2135);
DISPLAY 0.680851 (-4235 2135);
PAINT MONO (-4235 2135);
FORCEPROP 0 LASTPIN (-4225 2025) $PN 3
J 2
(-4235 2035);
DISPLAY 0.680851 (-4235 2035);
PAINT MONO (-4235 2035);
FORCEPROP 0 LASTPIN (-3425 1925) $PN 5
J 0
(-3415 1935);
DISPLAY 0.680851 (-3415 1935);
PAINT MONO (-3415 1935);
FORCEPROP 0 LASTPIN (-3425 2225) $PN 8
J 0
(-3415 2235);
DISPLAY 0.680851 (-3415 2235);
PAINT MONO (-3415 2235);
FORCEPROP 0 LASTPIN (-3425 2125) $PN 7
J 0
(-3415 2135);
DISPLAY 0.680851 (-3415 2135);
PAINT MONO (-3415 2135);
FORCEPROP 0 LASTPIN (-4225 1925) $PN 4
J 2
(-4235 1935);
DISPLAY 0.680851 (-4235 1935);
PAINT MONO (-4235 1935);
FORCEPROP 0 LASTPIN (-4225 2225) $PN 1
J 2
(-4235 2235);
DISPLAY 0.680851 (-4235 2235);
PAINT MONO (-4235 2235);
FORCEPROP 0 LAST ROOM HSC BOM2
J 0
(-4075 2575);
DISPLAY 0.680851 (-4075 2575);
FORCEPROP 1 LAST MATERIAL IC
J 0
(-4070 2282);
DISPLAY 0.723404 (-4070 2282);
PAINT GREEN (-4070 2282);
FORCEPROP 2 LAST VALUE NCT7718W
J 0
(-4075 1825);
DISPLAY 0.510638 (-4075 1825);
PAINT GREEN (-4075 1825);
FORCEPROP 2 LAST PART_TYPE SMLF
J 0
(-4075 1775);
DISPLAY 0.510638 (-4075 1775);
PAINT GREEN (-4075 1775);
FORCEPROP 1 LAST NEEDS_NO_SIZE TRUE
J 0
(-3825 2075);
DISPLAY 0.723404 (-3825 2075);
PAINT GREEN (-3825 2075);
DISPLAY INVISIBLE (-3825 2075);
FORCEPROP 2 LAST CDS_LIB pure_quanta
J 0
(-3825 2075);
DISPLAY INVISIBLE (-3825 2075);
FORCEPROP 1 LAST CDS_LMAN_SYM_OUTLINE -250,200,250,-200
J 0
(-3825 2075);
DISPLAY 0.468085 (-3825 2075);
PAINT GREEN (-3825 2075);
DISPLAY INVISIBLE (-3825 2075);
FORCEPROP 1 LAST PATH I8
J 0
(-3825 2075);
DISPLAY 0.723404 (-3825 2075);
PAINT GREEN (-3825 2075);
DISPLAY INVISIBLE (-3825 2075);
FORCEPROP 1 LAST PART_NUMBER AL007718001
J 0
(-4070 2409);
DISPLAY 0.723404 (-4070 2409);
PAINT GREEN (-4070 2409);
DISPLAY INVISIBLE (-4070 2409);
FORCEADD UNIVERSAL_GND..1
(-8900 2550);
FORCEPROP 3 LASTPIN (-8900 2600) SIG_NAME GND\g
J 0
(-8890 2610);
DISPLAY 0.659574 (-8890 2610);
PAINT MONO (-8890 2610);
DISPLAY INVISIBLE (-8890 2610);
FORCEPROP 2 LAST CDS_LIB pure_quanta_power
J 0
(-8900 2550);
DISPLAY INVISIBLE (-8900 2550);
FORCEPROP 1 LAST HDL_POWER GND
J 1
(-8875 2475);
DISPLAY 0.872340 (-8875 2475);
PAINT GREEN (-8875 2475);
DISPLAY INVISIBLE (-8875 2475);
FORCEPROP 1 LAST PATH I80
J 0
(-8825 2550);
DISPLAY 0.872340 (-8825 2550);
PAINT AQUA (-8825 2550);
DISPLAY INVISIBLE (-8825 2550);
FORCEADD Q_RES..2
(-8925 3700);
FORCEPROP 1 LAST LOCATION R8107
J 0
(-8880 3825);
DISPLAY 0.978723 (-8880 3825);
FORCEPROP 0 LAST $SEC 1
J 0
(-8875 3875);
DISPLAY 0.680851 (-8875 3875);
PAINT MONO (-8875 3875);
DISPLAY INVISIBLE (-8875 3875);
FORCEPROP 0 LAST CDS_SEC 1
J 0
(-8875 3875);
DISPLAY 1.021277 (-8875 3875);
DISPLAY INVISIBLE (-8875 3875);
FORCEPROP 1 LASTPIN (-8925 3800) $PN 1
J 0
(-8920 3762);
DISPLAY 0.787234 (-8920 3762);
PAINT MONO (-8920 3762);
FORCEPROP 1 LASTPIN (-8925 3600) $PN 2
J 0
(-8920 3610);
DISPLAY 0.787234 (-8920 3610);
PAINT MONO (-8920 3610);
FORCEPROP 1 LAST PACK_TYPE 0402LF
J 0
(-8875 3575);
DISPLAY 0.723404 (-8875 3575);
FORCEPROP 0 LAST ROOM HSC BOM2
J 0
(-8875 3875);
DISPLAY 0.680851 (-8875 3875);
FORCEPROP 1 LAST MATERIAL EMPTY
J 0
(-8885 3625);
DISPLAY 0.723404 (-8885 3625);
PAINT RED (-8885 3625);
FORCEPROP 1 LAST TOLERANCE 1%
J 0
(-8880 3725);
DISPLAY 0.723404 (-8880 3725);
FORCEPROP 1 LAST WATTAGE 1/16W
J 0
(-8885 3675);
DISPLAY 0.723404 (-8885 3675);
FORCEPROP 1 LAST VALUE 10K
J 0
(-8880 3775);
DISPLAY 0.723404 (-8880 3775);
FORCEPROP 2 LAST CDS_LIB pure_quanta
J 0
(-8925 3700);
DISPLAY INVISIBLE (-8925 3700);
FORCEPROP 1 LAST PATH I81
J 0
(-8875 3875);
DISPLAY 0.978723 (-8875 3875);
PAINT WHITE (-8875 3875);
DISPLAY INVISIBLE (-8875 3875);
FORCEPROP 1 LAST PART_NUMBER CS31002FB08
J 0
(-8885 3575);
DISPLAY 0.723404 (-8885 3575);
PAINT WHITE (-8885 3575);
DISPLAY INVISIBLE (-8885 3575);
FORCEADD Q_RES..2
(-7925 3075);
FORCEPROP 1 LAST LOCATION R8109
J 0
(-7880 3200);
DISPLAY 0.978723 (-7880 3200);
FORCEPROP 0 LAST $SEC 1
J 0
(-7875 3250);
DISPLAY 0.680851 (-7875 3250);
PAINT MONO (-7875 3250);
DISPLAY INVISIBLE (-7875 3250);
FORCEPROP 0 LAST CDS_SEC 1
J 0
(-7875 3250);
DISPLAY 1.021277 (-7875 3250);
DISPLAY INVISIBLE (-7875 3250);
FORCEPROP 1 LASTPIN (-7925 3175) $PN 1
J 0
(-7920 3137);
DISPLAY 0.787234 (-7920 3137);
PAINT MONO (-7920 3137);
FORCEPROP 1 LASTPIN (-7925 2975) $PN 2
J 0
(-7920 2985);
DISPLAY 0.787234 (-7920 2985);
PAINT MONO (-7920 2985);
FORCEPROP 0 LAST ROOM HSC BOM2
J 0
(-7875 3300);
DISPLAY 0.680851 (-7875 3300);
FORCEPROP 1 LAST MATERIAL EMPTY
J 0
(-7900 3000);
DISPLAY 0.787234 (-7900 3000);
PAINT RED (-7900 3000);
FORCEPROP 1 LAST VALUE 10K
J 0
(-7895 3150);
DISPLAY 0.787234 (-7895 3150);
FORCEPROP 1 LAST WATTAGE 1/16W
J 0
(-7900 3050);
DISPLAY 0.787234 (-7900 3050);
FORCEPROP 1 LAST TOLERANCE 1%
J 0
(-7895 3100);
DISPLAY 0.787234 (-7895 3100);
FORCEPROP 1 LAST PACK_TYPE 0402LF
J 0
(-7900 2900);
DISPLAY 0.787234 (-7900 2900);
FORCEPROP 2 LAST CDS_LIB pure_quanta
J 0
(-7925 3075);
DISPLAY INVISIBLE (-7925 3075);
FORCEPROP 1 LAST PATH I82
J 0
(-7875 3250);
DISPLAY 0.978723 (-7875 3250);
PAINT WHITE (-7875 3250);
DISPLAY INVISIBLE (-7875 3250);
FORCEPROP 1 LAST PART_NUMBER CS31002FB08
J 0
(-7900 2950);
DISPLAY 0.787234 (-7900 2950);
DISPLAY INVISIBLE (-7900 2950);
FORCEADD UNIVERSAL_GND..1
(-7925 2800);
FORCEPROP 3 LASTPIN (-7925 2850) SIG_NAME GND\g
J 0
(-7915 2860);
DISPLAY 0.659574 (-7915 2860);
PAINT MONO (-7915 2860);
DISPLAY INVISIBLE (-7915 2860);
FORCEPROP 2 LAST CDS_LIB pure_quanta_power
J 0
(-7925 2800);
DISPLAY INVISIBLE (-7925 2800);
FORCEPROP 1 LAST HDL_POWER GND
J 1
(-7900 2725);
DISPLAY 0.872340 (-7900 2725);
PAINT GREEN (-7900 2725);
DISPLAY INVISIBLE (-7900 2725);
FORCEPROP 1 LAST PATH I83
J 0
(-7850 2800);
DISPLAY 0.872340 (-7850 2800);
PAINT AQUA (-7850 2800);
DISPLAY INVISIBLE (-7850 2800);
FORCEADD Q_RES..2
(-7925 3750);
FORCEPROP 1 LAST LOCATION R8108
J 0
(-7875 3900);
DISPLAY 0.978723 (-7875 3900);
FORCEPROP 0 LAST $SEC 1
J 0
(-7875 3925);
DISPLAY 0.680851 (-7875 3925);
PAINT MONO (-7875 3925);
DISPLAY INVISIBLE (-7875 3925);
FORCEPROP 0 LAST CDS_SEC 1
J 0
(-7875 3925);
DISPLAY 1.021277 (-7875 3925);
DISPLAY INVISIBLE (-7875 3925);
FORCEPROP 1 LASTPIN (-7925 3850) $PN 1
J 0
(-7920 3812);
DISPLAY 0.787234 (-7920 3812);
PAINT MONO (-7920 3812);
FORCEPROP 1 LASTPIN (-7925 3650) $PN 2
J 0
(-7920 3660);
DISPLAY 0.787234 (-7920 3660);
PAINT MONO (-7920 3660);
FORCEPROP 1 LAST WATTAGE 1/16W
J 0
(-7875 3750);
DISPLAY 0.808511 (-7875 3750);
FORCEPROP 1 LAST TOLERANCE 1%
J 0
(-7875 3800);
DISPLAY 0.808511 (-7875 3800);
FORCEPROP 1 LAST VALUE 160K
J 0
(-7875 3850);
DISPLAY 0.808511 (-7875 3850);
FORCEPROP 0 LAST ROOM HSC BOM2
J 0
(-7875 4000);
DISPLAY 0.680851 (-7875 4000);
FORCEPROP 1 LAST PACK_TYPE 0402LF
J 0
(-7875 3600);
DISPLAY 0.808511 (-7875 3600);
FORCEPROP 1 LAST MATERIAL EMPTY
J 0
(-7875 3700);
DISPLAY 0.808511 (-7875 3700);
PAINT RED (-7875 3700);
FORCEPROP 2 LAST CDS_LIB pure_quanta
J 0
(-7925 3750);
DISPLAY INVISIBLE (-7925 3750);
FORCEPROP 1 LAST PATH I84
J 0
(-7875 3925);
DISPLAY 0.978723 (-7875 3925);
PAINT WHITE (-7875 3925);
DISPLAY INVISIBLE (-7875 3925);
FORCEPROP 1 LAST PART_NUMBER CS41602FB05
J 0
(-7875 3650);
DISPLAY 0.808511 (-7875 3650);
DISPLAY INVISIBLE (-7875 3650);
FORCEADD UNIVERSAL_POWER..1
(-8925 4025);
FORCEPROP 3 LASTPIN (-8925 3975) SIG_NAME P3V3_AUX\g
J 0
(-8915 3985);
DISPLAY 0.659574 (-8915 3985);
PAINT MONO (-8915 3985);
DISPLAY INVISIBLE (-8915 3985);
FORCEPROP 1 LAST HDL_POWER P3V3_AUX
J 1
(-8925 4075);
DISPLAY 0.723404 (-8925 4075);
PAINT GREEN (-8925 4075);
FORCEPROP 2 LAST CDS_LIB pure_quanta_power
J 0
(-8925 4025);
DISPLAY INVISIBLE (-8925 4025);
FORCEPROP 1 LAST PATH I85
J 0
(-8875 4050);
DISPLAY 0.872340 (-8875 4050);
PAINT AQUA (-8875 4050);
DISPLAY INVISIBLE (-8875 4050);
FORCEADD UNIVERSAL_GND..1
(-7525 2800);
FORCEPROP 3 LASTPIN (-7525 2850) SIG_NAME GND\g
J 0
(-7515 2860);
DISPLAY 0.659574 (-7515 2860);
PAINT MONO (-7515 2860);
DISPLAY INVISIBLE (-7515 2860);
FORCEPROP 2 LAST CDS_LIB pure_quanta_power
J 0
(-7525 2800);
DISPLAY INVISIBLE (-7525 2800);
FORCEPROP 1 LAST HDL_POWER GND
J 1
(-7500 2725);
DISPLAY 0.872340 (-7500 2725);
PAINT GREEN (-7500 2725);
DISPLAY INVISIBLE (-7500 2725);
FORCEPROP 1 LAST PATH I86
J 0
(-7450 2800);
DISPLAY 0.872340 (-7450 2800);
PAINT AQUA (-7450 2800);
DISPLAY INVISIBLE (-7450 2800);
FORCEADD Q_CAP..1
R 2
(-7525 3075);
FORCEPROP 1 LAST LOCATION C8014
J 2
(-7325 3200);
DISPLAY 0.638298 (-7325 3200);
FORCEPROP 0 LAST $SEC 1
J 0
(-7400 3250);
DISPLAY 0.680851 (-7400 3250);
PAINT MONO (-7400 3250);
DISPLAY INVISIBLE (-7400 3250);
FORCEPROP 0 LAST CDS_SEC 1
J 0
(-7400 3250);
DISPLAY 1.021277 (-7400 3250);
DISPLAY INVISIBLE (-7400 3250);
FORCEPROP 1 LASTPIN (-7525 3175) $PN 1
J 2
(-7535 3155);
DISPLAY 0.787234 (-7535 3155);
PAINT MONO (-7535 3155);
FORCEPROP 1 LASTPIN (-7525 2975) $PN 2
J 2
(-7535 2955);
DISPLAY 0.787234 (-7535 2955);
PAINT MONO (-7535 2955);
FORCEPROP 1 LAST VALUE 100NF
J 0
(-7450 3150);
DISPLAY 0.638298 (-7450 3150);
FORCEPROP 1 LAST VOLTAGE 50V
J 0
(-7450 3100);
DISPLAY 0.638298 (-7450 3100);
FORCEPROP 1 LAST TOLERANCE 10%
J 0
(-7450 3050);
DISPLAY 0.638298 (-7450 3050);
FORCEPROP 1 LAST PACK_TYPE C0402
J 0
(-7450 2900);
DISPLAY 0.638298 (-7450 2900);
FORCEPROP 1 LAST MATERIAL EMPTY
J 0
(-7450 2975);
DISPLAY 0.638298 (-7450 2975);
PAINT RED (-7450 2975);
FORCEPROP 0 LAST ROOM HSC BOM2
J 0
(-7500 3250);
DISPLAY 0.680851 (-7500 3250);
FORCEPROP 2 LAST CDS_LIB pure_quanta
J 0
(-7525 3075);
DISPLAY INVISIBLE (-7525 3075);
FORCEPROP 1 LAST PATH I87
J 2
(-7575 3225);
DISPLAY 0.978723 (-7575 3225);
PAINT WHITE (-7575 3225);
DISPLAY INVISIBLE (-7575 3225);
FORCEPROP 1 LAST PART_NUMBER CH4106K1B01
J 0
(-7450 2950);
DISPLAY 0.638298 (-7450 2950);
DISPLAY INVISIBLE (-7450 2950);
FORCEADD UNIVERSAL_GND..1
(-7100 2800);
FORCEPROP 3 LASTPIN (-7100 2850) SIG_NAME GND\g
J 0
(-7090 2860);
DISPLAY 0.659574 (-7090 2860);
PAINT MONO (-7090 2860);
DISPLAY INVISIBLE (-7090 2860);
FORCEPROP 2 LAST CDS_LIB pure_quanta_power
J 0
(-7100 2800);
DISPLAY INVISIBLE (-7100 2800);
FORCEPROP 1 LAST HDL_POWER GND
J 1
(-7075 2725);
DISPLAY 0.872340 (-7075 2725);
PAINT GREEN (-7075 2725);
DISPLAY INVISIBLE (-7075 2725);
FORCEPROP 1 LAST PATH I88
J 0
(-7025 2800);
DISPLAY 0.872340 (-7025 2800);
PAINT AQUA (-7025 2800);
DISPLAY INVISIBLE (-7025 2800);
FORCEADD Q_CAP..1
R 2
(-7100 3075);
FORCEPROP 1 LAST LOCATION C8015
J 2
(-6875 3200);
DISPLAY 0.787234 (-6875 3200);
FORCEPROP 0 LAST $SEC 1
J 0
(-6975 3250);
DISPLAY 0.680851 (-6975 3250);
PAINT MONO (-6975 3250);
DISPLAY INVISIBLE (-6975 3250);
FORCEPROP 0 LAST CDS_SEC 1
J 0
(-6975 3250);
DISPLAY 1.021277 (-6975 3250);
DISPLAY INVISIBLE (-6975 3250);
FORCEPROP 1 LASTPIN (-7100 3175) $PN 1
J 2
(-7110 3155);
DISPLAY 0.787234 (-7110 3155);
PAINT MONO (-7110 3155);
FORCEPROP 1 LASTPIN (-7100 2975) $PN 2
J 2
(-7110 2955);
DISPLAY 0.787234 (-7110 2955);
PAINT MONO (-7110 2955);
FORCEPROP 1 LAST TOLERANCE 10%
J 0
(-7025 3050);
DISPLAY 0.638298 (-7025 3050);
FORCEPROP 1 LAST MATERIAL EMPTY
J 0
(-7025 2975);
DISPLAY 0.638298 (-7025 2975);
PAINT RED (-7025 2975);
FORCEPROP 1 LAST VOLTAGE 50V
J 0
(-7025 3100);
DISPLAY 0.638298 (-7025 3100);
FORCEPROP 1 LAST PACK_TYPE C0402
J 0
(-7025 2900);
DISPLAY 0.638298 (-7025 2900);
FORCEPROP 0 LAST ROOM HSC BOM2
J 0
(-7075 3250);
DISPLAY 0.680851 (-7075 3250);
FORCEPROP 1 LAST VALUE 100NF
J 0
(-7025 3150);
DISPLAY 0.638298 (-7025 3150);
FORCEPROP 2 LAST CDS_LIB pure_quanta
J 0
(-7100 3075);
DISPLAY INVISIBLE (-7100 3075);
FORCEPROP 1 LAST PATH I89
J 2
(-7150 3225);
DISPLAY 0.978723 (-7150 3225);
PAINT WHITE (-7150 3225);
DISPLAY INVISIBLE (-7150 3225);
FORCEPROP 1 LAST PART_NUMBER CH4106K1B01
J 0
(-7025 2950);
DISPLAY 0.638298 (-7025 2950);
DISPLAY INVISIBLE (-7025 2950);
FORCEADD UNIVERSAL_GND..1
(-3325 1800);
FORCEPROP 3 LASTPIN (-3325 1850) SIG_NAME GND\g
J 0
(-3315 1860);
DISPLAY 0.659574 (-3315 1860);
PAINT MONO (-3315 1860);
DISPLAY INVISIBLE (-3315 1860);
FORCEPROP 2 LAST CDS_LIB pure_quanta_power
J 0
(-3325 1800);
DISPLAY INVISIBLE (-3325 1800);
FORCEPROP 1 LAST HDL_POWER GND
J 1
(-3300 1725);
DISPLAY 0.702128 (-3300 1725);
PAINT GREEN (-3300 1725);
DISPLAY INVISIBLE (-3300 1725);
FORCEPROP 1 LAST PATH I9
J 0
(-3250 1800);
DISPLAY 0.872340 (-3250 1800);
PAINT AQUA (-3250 1800);
DISPLAY INVISIBLE (-3250 1800);
FORCEADD UNIVERSAL_GND..1
(-6750 3050);
FORCEPROP 3 LASTPIN (-6750 3100) SIG_NAME GND\g
J 0
(-6740 3110);
DISPLAY 0.659574 (-6740 3110);
PAINT MONO (-6740 3110);
DISPLAY INVISIBLE (-6740 3110);
FORCEPROP 2 LAST CDS_LIB pure_quanta_power
J 0
(-6750 3050);
DISPLAY INVISIBLE (-6750 3050);
FORCEPROP 1 LAST HDL_POWER GND
J 1
(-6725 2975);
DISPLAY 0.872340 (-6725 2975);
PAINT GREEN (-6725 2975);
DISPLAY INVISIBLE (-6725 2975);
FORCEPROP 1 LAST PATH I90
J 0
(-6675 3050);
DISPLAY 0.872340 (-6675 3050);
PAINT AQUA (-6675 3050);
DISPLAY INVISIBLE (-6675 3050);
FORCEADD UNIVERSAL_POWER..1
(-6750 4325);
FORCEPROP 3 LASTPIN (-6750 4275) SIG_NAME P12V_AUX\g
J 0
(-6740 4285);
DISPLAY 0.659574 (-6740 4285);
PAINT MONO (-6740 4285);
DISPLAY INVISIBLE (-6740 4285);
FORCEPROP 1 LAST HDL_POWER P12V_AUX
J 1
(-6750 4375);
DISPLAY 0.723404 (-6750 4375);
PAINT GREEN (-6750 4375);
FORCEPROP 2 LAST CDS_LIB pure_quanta_power
J 0
(-6750 4325);
DISPLAY INVISIBLE (-6750 4325);
FORCEPROP 1 LAST PATH I93
J 0
(-6700 4350);
DISPLAY 0.872340 (-6700 4350);
PAINT AQUA (-6700 4350);
DISPLAY INVISIBLE (-6700 4350);
FORCEADD UNIVERSAL_GND..1
(-6500 3900);
FORCEPROP 3 LASTPIN (-6500 3950) SIG_NAME GND\g
J 0
(-6490 3960);
DISPLAY 0.659574 (-6490 3960);
PAINT MONO (-6490 3960);
DISPLAY INVISIBLE (-6490 3960);
FORCEPROP 2 LAST CDS_LIB pure_quanta_power
J 0
(-6500 3900);
DISPLAY INVISIBLE (-6500 3900);
FORCEPROP 1 LAST HDL_POWER GND
J 1
(-6475 3825);
DISPLAY 0.872340 (-6475 3825);
PAINT GREEN (-6475 3825);
DISPLAY INVISIBLE (-6475 3825);
FORCEPROP 1 LAST PATH I94
J 0
(-6425 3900);
DISPLAY 0.872340 (-6425 3900);
PAINT AQUA (-6425 3900);
DISPLAY INVISIBLE (-6425 3900);
FORCEADD Q_CAP..1
R 2
(-6500 4100);
FORCEPROP 1 LAST LOCATION C8016
J 0
(-6425 4225);
DISPLAY 0.787234 (-6425 4225);
FORCEPROP 0 LAST $SEC 1
J 0
(-6425 4275);
DISPLAY 0.680851 (-6425 4275);
PAINT MONO (-6425 4275);
DISPLAY INVISIBLE (-6425 4275);
FORCEPROP 0 LAST CDS_SEC 1
J 0
(-6425 4275);
DISPLAY 1.021277 (-6425 4275);
DISPLAY INVISIBLE (-6425 4275);
FORCEPROP 1 LASTPIN (-6500 4200) $PN 1
J 2
(-6510 4180);
DISPLAY 0.787234 (-6510 4180);
PAINT MONO (-6510 4180);
FORCEPROP 1 LASTPIN (-6500 4000) $PN 2
J 2
(-6510 3980);
DISPLAY 0.787234 (-6510 3980);
PAINT MONO (-6510 3980);
FORCEPROP 1 LAST VALUE 100NF
J 0
(-6425 4175);
DISPLAY 0.787234 (-6425 4175);
FORCEPROP 1 LAST MATERIAL EMPTY
J 0
(-6425 4025);
DISPLAY 0.787234 (-6425 4025);
PAINT RED (-6425 4025);
FORCEPROP 1 LAST TOLERANCE 10%
J 0
(-6425 4075);
DISPLAY 0.787234 (-6425 4075);
FORCEPROP 1 LAST VOLTAGE 50V
J 0
(-6425 4125);
DISPLAY 0.787234 (-6425 4125);
FORCEPROP 0 LAST ROOM HSC BOM2
J 0
(-6425 4300);
DISPLAY 0.680851 (-6425 4300);
FORCEPROP 1 LAST PACK_TYPE C0402
J 0
(-6425 3925);
DISPLAY 0.787234 (-6425 3925);
FORCEPROP 2 LAST CDS_LIB pure_quanta
J 0
(-6500 4100);
DISPLAY INVISIBLE (-6500 4100);
FORCEPROP 1 LAST PATH I95
J 2
(-6550 4250);
DISPLAY 0.978723 (-6550 4250);
PAINT WHITE (-6550 4250);
DISPLAY INVISIBLE (-6550 4250);
FORCEPROP 1 LAST PART_NUMBER CH4106K1B01
J 0
(-6425 3975);
DISPLAY 0.787234 (-6425 3975);
DISPLAY INVISIBLE (-6425 3975);
FORCEADD Q_RES..1
(-5375 3475);
FORCEPROP 1 LAST LOCATION R8110
J 0
(-5650 3475);
DISPLAY 0.978723 (-5650 3475);
FORCEPROP 0 LAST $SEC 1
J 0
(-5525 3525);
DISPLAY 0.680851 (-5525 3525);
PAINT MONO (-5525 3525);
DISPLAY INVISIBLE (-5525 3525);
FORCEPROP 0 LAST CDS_SEC 1
J 0
(-5525 3525);
DISPLAY 1.021277 (-5525 3525);
DISPLAY INVISIBLE (-5525 3525);
FORCEPROP 1 LASTPIN (-5475 3475) $PN 1
J 0
(-5463 3487);
DISPLAY 0.787234 (-5463 3487);
PAINT MONO (-5463 3487);
FORCEPROP 1 LASTPIN (-5275 3475) $PN 2
J 0
(-5313 3487);
DISPLAY 0.787234 (-5313 3487);
PAINT MONO (-5313 3487);
FORCEPROP 1 LAST VALUE 33.2
J 2
(-5175 3475);
DISPLAY 0.510638 (-5175 3475);
FORCEPROP 1 LAST MATERIAL EMPTY
J 0
(-5675 3425);
DISPLAY 0.808511 (-5675 3425);
PAINT RED (-5675 3425);
FORCEPROP 1 LAST TOLERANCE 1%
J 0
(-5150 3475);
DISPLAY 0.510638 (-5150 3475);
FORCEPROP 0 LAST ROOM HSC BOM2
J 0
(-5250 3425);
DISPLAY 0.680851 (-5250 3425);
FORCEPROP 1 LAST PACK_TYPE 0402LF
J 0
(-5375 3575);
DISPLAY 0.404255 (-5375 3575);
DISPLAY INVISIBLE (-5375 3575);
FORCEPROP 1 LAST WATTAGE 1/16W
J 2
(-5150 3575);
DISPLAY 0.404255 (-5150 3575);
DISPLAY INVISIBLE (-5150 3575);
FORCEPROP 2 LAST CDS_LIB pure_quanta
J 0
(-5375 3475);
DISPLAY INVISIBLE (-5375 3475);
FORCEPROP 1 LAST PATH I96
J 0
(-5425 3625);
DISPLAY 0.978723 (-5425 3625);
PAINT WHITE (-5425 3625);
DISPLAY INVISIBLE (-5425 3625);
FORCEPROP 1 LAST PART_NUMBER CS03322FB03
J 0
(-5475 3550);
DISPLAY 0.404255 (-5475 3550);
DISPLAY INVISIBLE (-5475 3550);
FORCEADD Q_RES..2
(-4550 3750);
FORCEPROP 1 LAST LOCATION R8111
J 0
(-4505 3875);
DISPLAY 0.978723 (-4505 3875);
FORCEPROP 0 LAST $SEC 1
J 0
(-4500 3925);
DISPLAY 0.680851 (-4500 3925);
PAINT MONO (-4500 3925);
DISPLAY INVISIBLE (-4500 3925);
FORCEPROP 0 LAST CDS_SEC 1
J 0
(-4500 3925);
DISPLAY 1.021277 (-4500 3925);
DISPLAY INVISIBLE (-4500 3925);
FORCEPROP 1 LASTPIN (-4550 3850) $PN 1
J 0
(-4545 3812);
DISPLAY 0.787234 (-4545 3812);
PAINT MONO (-4545 3812);
FORCEPROP 1 LASTPIN (-4550 3650) $PN 2
J 0
(-4545 3660);
DISPLAY 0.787234 (-4545 3660);
PAINT MONO (-4545 3660);
FORCEPROP 0 LAST ROOM HSC BOM2
J 0
(-4500 3975);
DISPLAY 0.680851 (-4500 3975);
FORCEPROP 1 LAST TOLERANCE 1%
J 0
(-4505 3775);
DISPLAY 0.723404 (-4505 3775);
FORCEPROP 1 LAST VALUE 10K
J 0
(-4505 3825);
DISPLAY 0.723404 (-4505 3825);
FORCEPROP 1 LAST WATTAGE 1/16W
J 0
(-4510 3725);
DISPLAY 0.723404 (-4510 3725);
FORCEPROP 1 LAST MATERIAL EMPTY
J 0
(-4510 3675);
DISPLAY 0.723404 (-4510 3675);
PAINT RED (-4510 3675);
FORCEPROP 1 LAST PACK_TYPE 0402LF
J 0
(-4500 3625);
DISPLAY 0.723404 (-4500 3625);
FORCEPROP 2 LAST CDS_LIB pure_quanta
J 0
(-4550 3750);
DISPLAY INVISIBLE (-4550 3750);
FORCEPROP 1 LAST PATH I98
J 0
(-4500 3925);
DISPLAY 0.978723 (-4500 3925);
PAINT WHITE (-4500 3925);
DISPLAY INVISIBLE (-4500 3925);
FORCEPROP 1 LAST PART_NUMBER CS31002FB08
J 0
(-4510 3625);
DISPLAY 0.723404 (-4510 3625);
PAINT WHITE (-4510 3625);
DISPLAY INVISIBLE (-4510 3625);
FORCEADD OFFPAGE..2
(-4250 3475);
FORCEPROP 2 LAST $XR0 268 
J 0
(-4061 3475);
DISPLAY 0.638298 (-4061 3475);
PAINT MONO (-4061 3475);
FORCEPROP 2 LAST CDS_LIB standard
J 0
(-4250 3475);
DISPLAY INVISIBLE (-4250 3475);
FORCEPROP 1 LAST OFFPAGE TRUE
J 0
(-3925 3350);
DISPLAY 0.872340 (-3925 3350);
PAINT AQUA (-3925 3350);
DISPLAY INVISIBLE (-3925 3350);
FORCEPROP 1 LAST COMMENT_BODY TRUE
J 0
(-4295 3380);
DISPLAY 0.872340 (-4295 3380);
PAINT GREEN (-4295 3380);
DISPLAY INVISIBLE (-4295 3380);
FORCEPROP 2 LAST PATH I99
J 0
(-4050 3525);
DISPLAY 0.680851 (-4050 3525);
DISPLAY INVISIBLE (-4050 3525);
FORCEADD DNS..1
(-8900 3650);
PAINT RED (-8900 3650);
FORCEPROP 2 LAST CDS_LIB mstr_misc
J 0
(-8900 3650);
DISPLAY INVISIBLE (-8900 3650);
FORCEPROP 1 LAST COMMENT_BODY TRUE
R 1
J 0
(-8825 3425);
DISPLAY 0.872340 (-8825 3425);
PAINT GREEN (-8825 3425);
DISPLAY INVISIBLE (-8825 3425);
FORCEADD DNS..1
(-8525 2825);
PAINT RED (-8525 2825);
FORCEPROP 2 LAST CDS_LIB mstr_misc
J 0
(-8525 2825);
DISPLAY INVISIBLE (-8525 2825);
FORCEPROP 1 LAST COMMENT_BODY TRUE
R 1
J 0
(-8450 2600);
DISPLAY 0.872340 (-8450 2600);
PAINT GREEN (-8450 2600);
DISPLAY INVISIBLE (-8450 2600);
FORCEADD DNS..2
(-4400 5500);
PAINT RED (-4400 5500);
FORCEPROP 2 LAST CDS_LIB mstr_misc
J 0
(-4400 5500);
DISPLAY INVISIBLE (-4400 5500);
FORCEPROP 1 LAST COMMENT_BODY TRUE
R 1
J 0
(-4325 5275);
DISPLAY 0.872340 (-4325 5275);
PAINT GREEN (-4325 5275);
DISPLAY INVISIBLE (-4325 5275);
FORCEADD DNS..2
(-2750 6225);
PAINT RED (-2750 6225);
FORCEPROP 2 LAST CDS_LIB mstr_misc
J 0
(-2750 6225);
DISPLAY INVISIBLE (-2750 6225);
FORCEPROP 1 LAST COMMENT_BODY TRUE
R 1
J 0
(-2675 6000);
DISPLAY 0.872340 (-2675 6000);
PAINT GREEN (-2675 6000);
DISPLAY INVISIBLE (-2675 6000);
FORCEADD DNS..1
(-7525 3050);
PAINT RED (-7525 3050);
FORCEPROP 2 LAST CDS_LIB mstr_misc
J 0
(-7525 3050);
DISPLAY INVISIBLE (-7525 3050);
FORCEPROP 1 LAST COMMENT_BODY TRUE
R 1
J 0
(-7450 2825);
DISPLAY 0.872340 (-7450 2825);
PAINT GREEN (-7450 2825);
DISPLAY INVISIBLE (-7450 2825);
FORCEADD DNS..2
(-7275 5400);
PAINT RED (-7275 5400);
FORCEPROP 2 LAST CDS_LIB mstr_misc
J 0
(-7275 5400);
DISPLAY INVISIBLE (-7275 5400);
FORCEPROP 1 LAST COMMENT_BODY TRUE
R 1
J 0
(-7200 5175);
DISPLAY 0.872340 (-7200 5175);
PAINT GREEN (-7200 5175);
DISPLAY INVISIBLE (-7200 5175);
FORCEADD DNS..2
(-3425 6275);
PAINT RED (-3425 6275);
FORCEPROP 2 LAST CDS_LIB mstr_misc
J 0
(-3425 6275);
DISPLAY INVISIBLE (-3425 6275);
FORCEPROP 1 LAST COMMENT_BODY TRUE
R 1
J 0
(-3350 6050);
DISPLAY 0.872340 (-3350 6050);
PAINT GREEN (-3350 6050);
DISPLAY INVISIBLE (-3350 6050);
FORCEADD DNS..1
(-7925 3725);
PAINT RED (-7925 3725);
FORCEPROP 2 LAST CDS_LIB mstr_misc
J 0
(-7925 3725);
DISPLAY INVISIBLE (-7925 3725);
FORCEPROP 1 LAST COMMENT_BODY TRUE
R 1
J 0
(-7850 3500);
DISPLAY 0.872340 (-7850 3500);
PAINT GREEN (-7850 3500);
DISPLAY INVISIBLE (-7850 3500);
FORCEADD DNS..1
(-7100 3050);
PAINT RED (-7100 3050);
FORCEPROP 2 LAST CDS_LIB mstr_misc
J 0
(-7100 3050);
DISPLAY INVISIBLE (-7100 3050);
FORCEPROP 1 LAST COMMENT_BODY TRUE
R 1
J 0
(-7025 2825);
DISPLAY 0.872340 (-7025 2825);
PAINT GREEN (-7025 2825);
DISPLAY INVISIBLE (-7025 2825);
FORCEADD DNS..2
(-7750 5450);
PAINT RED (-7750 5450);
FORCEPROP 2 LAST CDS_LIB mstr_misc
J 0
(-7750 5450);
DISPLAY INVISIBLE (-7750 5450);
FORCEPROP 1 LAST COMMENT_BODY TRUE
R 1
J 0
(-7675 5225);
DISPLAY 0.872340 (-7675 5225);
PAINT GREEN (-7675 5225);
DISPLAY INVISIBLE (-7675 5225);
FORCEADD DNS..1
(-4550 3725);
PAINT RED (-4550 3725);
FORCEPROP 2 LAST CDS_LIB mstr_misc
J 0
(-4550 3725);
DISPLAY INVISIBLE (-4550 3725);
FORCEPROP 1 LAST COMMENT_BODY TRUE
R 1
J 0
(-4475 3500);
DISPLAY 0.872340 (-4475 3500);
PAINT GREEN (-4475 3500);
DISPLAY INVISIBLE (-4475 3500);
FORCEADD DNS..1
(-6775 3450);
PAINT RED (-6775 3450);
FORCEPROP 2 LAST CDS_LIB mstr_misc
J 0
(-6775 3450);
DISPLAY INVISIBLE (-6775 3450);
FORCEPROP 1 LAST COMMENT_BODY TRUE
R 1
J 0
(-6700 3225);
DISPLAY 0.872340 (-6700 3225);
PAINT GREEN (-6700 3225);
DISPLAY INVISIBLE (-6700 3225);
FORCEADD DNS..1
(-7925 3125);
PAINT RED (-7925 3125);
FORCEPROP 2 LAST CDS_LIB mstr_misc
J 0
(-7925 3125);
DISPLAY INVISIBLE (-7925 3125);
FORCEPROP 1 LAST COMMENT_BODY TRUE
R 1
J 0
(-7850 2900);
DISPLAY 0.872340 (-7850 2900);
PAINT GREEN (-7850 2900);
DISPLAY INVISIBLE (-7850 2900);
FORCEADD DNS..2
(-5475 5800);
PAINT RED (-5475 5800);
FORCEPROP 2 LAST CDS_LIB mstr_misc
J 0
(-5475 5800);
DISPLAY INVISIBLE (-5475 5800);
FORCEPROP 1 LAST COMMENT_BODY TRUE
R 1
J 0
(-5400 5575);
DISPLAY 0.872340 (-5400 5575);
PAINT GREEN (-5400 5575);
DISPLAY INVISIBLE (-5400 5575);
FORCEADD DNS..1
(-6500 4075);
PAINT RED (-6500 4075);
FORCEPROP 2 LAST CDS_LIB mstr_misc
J 0
(-6500 4075);
DISPLAY INVISIBLE (-6500 4075);
FORCEPROP 1 LAST COMMENT_BODY TRUE
R 1
J 0
(-6425 3850);
DISPLAY 0.872340 (-6425 3850);
PAINT GREEN (-6425 3850);
DISPLAY INVISIBLE (-6425 3850);
FORCEADD DNS..2
(-4425 6200);
PAINT RED (-4425 6200);
FORCEPROP 2 LAST CDS_LIB mstr_misc
J 0
(-4425 6200);
DISPLAY INVISIBLE (-4425 6200);
FORCEPROP 1 LAST COMMENT_BODY TRUE
R 1
J 0
(-4350 5975);
DISPLAY 0.872340 (-4350 5975);
PAINT GREEN (-4350 5975);
DISPLAY INVISIBLE (-4350 5975);
FORCEADD QUANTA_TITLE_BLOCK_C..1
(75 400);
FORCEPROP 0 LAST CDS_CON_LAST_MODIFIED Thu Sep 14 16:12:45 2023
J 0
(-1810 415);
DISPLAY INVISIBLE (-1810 415);
FORCEPROP 1 LAST CUSTOM_TXT_CDS <CON_LAST_MODIFIED>
J 0
(-1810 415);
DISPLAY 0.978723 (-1810 415);
FORCEPROP 2 LAST CUSTOM_TXT_CDS <XR_PAGE_TITLE>
J 0
(-7815 5650);
DISPLAY 0.638298 (-7815 5650);
PAINT PINK (-7815 5650);
DISPLAY INVISIBLE (-7815 5650);
FORCEPROP 1 LAST CUSTOM_TXT_CDS <NAME_2>
J 0
(-3100 450);
FORCEPROP 1 LAST CUSTOM_TXT_CDS <NAME_1>
J 0
(-3100 575);
FORCEPROP 1 LAST CUSTOM_TXT_CDS <Q_NUMBER>
J 0
(-1328 503);
DISPLAY 1.212766 (-1328 503);
FORCEPROP 1 LAST CUSTOM_TXT_CDS <Q_PROJ>
J 0
(-2307 502);
DISPLAY 1.212766 (-2307 502);
FORCEPROP 1 LAST CUSTOM_TXT_CDS <Q_REV>
J 0
(-109 503);
DISPLAY 1.212766 (-109 503);
FORCEPROP 1 LAST CUSTOM_TXT_CDS <CON_PAGE_NUM> OF <CON_TOTAL_PAGES>
J 0
(-371 418);
DISPLAY 0.978723 (-371 418);
FORCEPROP 1 LAST Q_TITLE P12V HOTSWAP FOR MODULE(2/2)
J 0
(-9291 426);
DISPLAY 2.446809 (-9291 426);
PAINT GREEN (-9291 426);
FORCEPROP 2 LAST PAGE_BORDER TRUE
J 0
(-7815 5650);
DISPLAY 0.638298 (-7815 5650);
PAINT PINK (-7815 5650);
DISPLAY INVISIBLE (-7815 5650);
FORCEPROP 2 LAST CDS_LIB pure_quanta
J 0
(75 400);
DISPLAY INVISIBLE (75 400);
FORCEPROP 1 LAST CDS_LMAN_SYM_OUTLINE -9475,6775,100,-125
J 0
(75 400);
DISPLAY 0.468085 (75 400);
PAINT GREEN (75 400);
DISPLAY INVISIBLE (75 400);
FORCEPROP 2 LAST CDS_XR_PAGE_TITLE CR-268 : @T6G_MB_LIB.T6G(SCH_1):PAGE268
J 0
(-7815 5650);
DISPLAY 0.638298 (-7815 5650);
PAINT PINK (-7815 5650);
DISPLAY INVISIBLE (-7815 5650);
FORCEPROP 1 LAST Q_DEPT BU9
J 1
(-3688 449);
DISPLAY 1.957447 (-3688 449);
PAINT GREEN (-3688 449);
DISPLAY INVISIBLE (-3688 449);
FORCEPROP 1 LAST COMMENT_BODY TRUE
J 0
(87 387);
DISPLAY 0.978723 (87 387);
PAINT GREEN (87 387);
DISPLAY INVISIBLE (87 387);
FORCEADD DNS..2
(-7750 6200);
PAINT RED (-7750 6200);
FORCEPROP 2 LAST CDS_LIB mstr_misc
J 0
(-7750 6200);
DISPLAY INVISIBLE (-7750 6200);
FORCEPROP 1 LAST COMMENT_BODY TRUE
R 1
J 0
(-7675 5975);
DISPLAY 0.872340 (-7675 5975);
PAINT GREEN (-7675 5975);
DISPLAY INVISIBLE (-7675 5975);
FORCEADD DNS..2
(-6375 6225);
PAINT RED (-6375 6225);
FORCEPROP 2 LAST CDS_LIB mstr_misc
J 0
(-6375 6225);
DISPLAY INVISIBLE (-6375 6225);
FORCEPROP 1 LAST COMMENT_BODY TRUE
R 1
J 0
(-6300 6000);
DISPLAY 0.872340 (-6300 6000);
PAINT GREEN (-6300 6000);
DISPLAY INVISIBLE (-6300 6000);
FORCEADD DNS..2
(-7300 6250);
PAINT RED (-7300 6250);
FORCEPROP 2 LAST CDS_LIB mstr_misc
J 0
(-7300 6250);
DISPLAY INVISIBLE (-7300 6250);
FORCEPROP 1 LAST COMMENT_BODY TRUE
R 1
J 0
(-7225 6025);
DISPLAY 0.872340 (-7225 6025);
PAINT GREEN (-7225 6025);
DISPLAY INVISIBLE (-7225 6025);
FORCEADD DNS..1
(-5350 3475);
PAINT RED (-5350 3475);
FORCEPROP 2 LAST CDS_LIB mstr_misc
J 0
(-5350 3475);
DISPLAY INVISIBLE (-5350 3475);
FORCEPROP 1 LAST COMMENT_BODY TRUE
R 1
J 0
(-5275 3250);
DISPLAY 0.872340 (-5275 3250);
PAINT GREEN (-5275 3250);
DISPLAY INVISIBLE (-5275 3250);
FORCEADD DNS..2
(-6750 6225);
PAINT RED (-6750 6225);
FORCEPROP 2 LAST CDS_LIB mstr_misc
J 0
(-6750 6225);
DISPLAY INVISIBLE (-6750 6225);
FORCEPROP 1 LAST COMMENT_BODY TRUE
R 1
J 0
(-6675 6000);
DISPLAY 0.872340 (-6675 6000);
PAINT GREEN (-6675 6000);
DISPLAY INVISIBLE (-6675 6000);
FORCEADD DNS..2
(-6375 6600);
PAINT RED (-6375 6600);
FORCEPROP 2 LAST CDS_LIB mstr_misc
J 0
(-6375 6600);
DISPLAY INVISIBLE (-6375 6600);
FORCEPROP 1 LAST COMMENT_BODY TRUE
R 1
J 0
(-6300 6375);
DISPLAY 0.872340 (-6300 6375);
PAINT GREEN (-6300 6375);
DISPLAY INVISIBLE (-6300 6375);
WIRE 16 -1 (-4550 4025)(-4550 3850);
WIRE 16 -1 (-6375 6775)(-6375 6725);
WIRE 16 -1 (-2700 4725)(-2700 4775);
WIRE 16 -1 (-925 3525)(-925 3500);
WIRE 16 -1 (-1400 4350)(-800 4350);
FORCEPROP 2 LAST SIG_NAME P12V_PSU
J 0
(-1310 4360);
DISPLAY 0.723404 (-1310 4360);
FORCEPROP 2 LASTPROP $XRERR UNIQUE?
J 0
(-1550 4360);
DISPLAY 0.638298 (-1550 4360);
PAINT MONO (-1550 4360);
DISPLAY INVISIBLE (-1550 4360);
WIRE 16 -1 (-800 4350)(-800 4400);
WIRE 16 -1 (-4750 2350)(-4750 2300);
WIRE 16 -1 (-5025 5700)(-5025 5450);
WIRE 16 -1 (-5025 5700)(-5125 5700);
WIRE 16 -1 (-4450 6475)(-4450 6325);
WIRE 16 -1 (-4450 5425)(-4450 5250);
WIRE 16 -1 (-3425 6075)(-3425 5950);
WIRE 16 -1 (-2300 6275)(-2300 6500);
WIRE 16 -1 (-2275 1700)(-2275 1800);
WIRE 16 -1 (-2125 2700)(-2125 2825);
WIRE 16 -1 (-8875 2725)(-8900 2725);
WIRE 16 -1 (-8900 2725)(-8900 2600);
WIRE 16 -1 (-7925 2850)(-7925 2975);
WIRE 16 -1 (-8925 3975)(-8925 3800);
WIRE 16 -1 (-7525 2850)(-7525 2975);
WIRE 16 -1 (-7100 2850)(-7100 2975);
WIRE 16 -1 (-3425 1925)(-3325 1925);
WIRE 16 -1 (-3325 1925)(-3325 1850);
WIRE 16 -1 (-6750 3100)(-6750 3225);
WIRE 16 -1 (-6500 3950)(-6500 4000);
WIRE 16 -1 (-925 3900)(-175 3900);
WIRE 16 -1 (-925 3900)(-925 3725);
WIRE 16 -1 (-1400 3900)(-925 3900);
FORCEPROP 2 LAST SIG_NAME P12V_AUX
J 0
(-1310 3910);
DISPLAY 0.723404 (-1310 3910);
FORCEPROP 2 LASTPROP $XRERR UNIQUE?
J 0
(-1550 3910);
DISPLAY 0.638298 (-1550 3910);
PAINT MONO (-1550 3910);
DISPLAY INVISIBLE (-1550 3910);
WIRE 16 -1 (-4350 2725)(-4575 2725);
WIRE 16 -1 (-4350 2725)(-4350 2225);
WIRE 16 -1 (-4575 2800)(-4575 2725);
WIRE 16 -1 (-4575 2725)(-4750 2725);
WIRE 16 -1 (-4750 2550)(-4750 2725);
WIRE 16 -1 (-4350 2225)(-4225 2225);
WIRE 16 -1 (-5125 5750)(-2775 5750);
WIRE 16 -1 (-2775 5750)(-2300 5750);
WIRE 16 -1 (-2775 6125)(-2775 5750);
WIRE 16 -1 (-2300 6075)(-2300 5750);
WIRE 16 -1 (-2225 5750)(-2300 5750);
WIRE 16 -1 (-1650 5750)(-2225 5750);
FORCEPROP 2 LAST SIG_NAME HSC_D_OC
J 0
(-2035 5760);
DISPLAY 0.680851 (-2035 5760);
WIRE 16 -1 (-2225 4925)(-2225 5750);
WIRE 16 -1 (-5175 4925)(-2225 4925);
WIRE 16 -1 (-2000 3950)(-2875 3950);
FORCEPROP 2 LAST SIG_NAME IRQ_SML1_PMBUS_ALERT_N
J 0
(-2860 3960);
DISPLAY 0.723404 (-2860 3960);
WIRE 16 -1 (-3025 4000)(-2000 4000);
FORCEPROP 2 LAST SIG_NAME SMB_SML1_PMBUS_HSC_R1_SDA
J 0
(-2910 4010);
DISPLAY 0.723404 (-2910 4010);
WIRE 16 -1 (-3025 4050)(-2000 4050);
FORCEPROP 2 LAST SIG_NAME SMB_SML1_PMBUS_HSC_R1_SCL
J 0
(-2910 4060);
DISPLAY 0.723404 (-2910 4060);
WIRE 16 -1 (-2000 4300)(-2700 4300);
WIRE 16 -1 (-2700 4525)(-2700 4300);
WIRE 16 -1 (-2700 4300)(-3375 4300);
FORCEPROP 2 LAST SIG_NAME IRQ_HSC_FAULT_N
J 0
(-3360 4310);
DISPLAY 0.723404 (-3360 4310);
WIRE 16 -1 (-2000 4150)(-2875 4150);
FORCEPROP 2 LAST SIG_NAME HSC_CSOUT
J 0
(-2860 4150);
DISPLAY 0.808511 (-2860 4150);
WIRE 16 -1 (-2875 4250)(-2000 4250);
FORCEPROP 2 LAST SIG_NAME HSC_EN
J 0
(-2860 4260);
DISPLAY 0.723404 (-2860 4260);
WIRE 16 -1 (-2400 4350)(-2000 4350);
WIRE 16 -1 (-2400 4400)(-2400 4350);
WIRE 16 -1 (-2875 4200)(-2000 4200);
FORCEPROP 2 LAST SIG_NAME MB0_P12V_STBY_PWRGD
J 0
(-2860 4210);
DISPLAY 0.723404 (-2860 4210);
WIRE 16 -1 (-2875 4100)(-2000 4100);
FORCEPROP 2 LAST SIG_NAME HSC_TYPE_ADC
J 0
(-2860 4110);
DISPLAY 0.808511 (-2860 4110);
WIRE 16 -1 (-2150 3700)(-2000 3700);
WIRE 16 -1 (-2150 3750)(-2150 3700);
WIRE 16 -1 (-2150 3575)(-2150 3700);
WIRE 16 -1 (-2000 3750)(-2150 3750);
WIRE 16 -1 (-2150 3900)(-2150 3750);
WIRE 16 -1 (-2150 3900)(-2000 3900);
WIRE 16 273 (-6600 2200)(-5500 2200);
WIRE 16 273 (-6600 1700)(-6600 2200);
WIRE 16 273 (-5500 1700)(-5500 2200);
WIRE 16 273 (-6600 1700)(-5500 1700);
WIRE 16 -1 (-5375 2125)(-6000 2125);
FORCEPROP 2 LAST SIG_NAME P12V_HSC_TEMP_R
J 0
(-6085 2135);
DISPLAY 0.723404 (-6085 2135);
FORCEPROP 2 LASTPROP $XRERR UNIQUE?
J 0
(-6325 2135);
DISPLAY 0.638298 (-6325 2135);
PAINT MONO (-6325 2135);
DISPLAY INVISIBLE (-6325 2135);
WIRE 16 -1 (-6000 2125)(-6000 1950);
WIRE 16 -1 (-6150 2125)(-6000 2125);
WIRE 16 -1 (-6150 2050)(-6150 2125);
WIRE 16 -1 (-4225 2125)(-4975 2125);
FORCEPROP 2 LAST SIG_NAME P12V_HSC_TEMP_D+
J 0
(-4760 2135);
DISPLAY 0.638298 (-4760 2135);
PAINT WHITE (-4760 2135);
FORCEPROP 2 LASTPROP $XRERR UNIQUE?
J 0
(-5000 2135);
DISPLAY 0.638298 (-5000 2135);
PAINT MONO (-5000 2135);
DISPLAY INVISIBLE (-5000 2135);
WIRE 16 -1 (-4975 2125)(-4975 2075);
WIRE 16 -1 (-5175 2125)(-4975 2125);
WIRE 16 -1 (-5200 1775)(-4975 1775);
WIRE 16 -1 (-4675 1775)(-4975 1775);
WIRE 16 -1 (-4975 1775)(-4975 1875);
WIRE 16 -1 (-4675 2025)(-4675 1775);
WIRE 16 -1 (-4225 2025)(-4675 2025);
FORCEPROP 2 LAST SIG_NAME P12V_HSC_TEMP_D-
J 0
(-4760 2035);
DISPLAY 0.638298 (-4760 2035);
PAINT WHITE (-4760 2035);
FORCEPROP 2 LASTPROP $XRERR UNIQUE?
J 0
(-5000 2035);
DISPLAY 0.638298 (-5000 2035);
PAINT MONO (-5000 2035);
DISPLAY INVISIBLE (-5000 2035);
WIRE 16 -1 (-4400 1250)(-3600 1250);
FORCEPROP 2 LAST SIG_NAME P12V_HSC_T_CRIT_N
J 0
(-4385 1260);
DISPLAY 0.680851 (-4385 1260);
FORCEPROP 2 LASTPROP $XRERR UNIQUE?
J 0
(-4625 1260);
DISPLAY 0.638298 (-4625 1260);
PAINT MONO (-4625 1260);
DISPLAY INVISIBLE (-4625 1260);
WIRE 16 -1 (-4400 1925)(-4400 1250);
WIRE 16 -1 (-4225 1925)(-4400 1925);
WIRE 16 -1 (-3425 2025)(-2600 2025);
FORCEPROP 2 LAST SIG_NAME P12V_HSC_TEMP_ALERT_N
J 0
(-3335 2035);
DISPLAY 0.510638 (-3335 2035);
PAINT WHITE (-3335 2035);
FORCEPROP 2 LASTPROP $XRERR UNIQUE?
J 0
(-3575 2035);
DISPLAY 0.638298 (-3575 2035);
PAINT MONO (-3575 2035);
DISPLAY INVISIBLE (-3575 2035);
WIRE 16 -1 (-3425 2125)(-2600 2125);
FORCEPROP 2 LAST SIG_NAME SMB_P12V_HSC_TEMP_SDA
J 0
(-3335 2135);
DISPLAY 0.510638 (-3335 2135);
PAINT WHITE (-3335 2135);
FORCEPROP 2 LASTPROP $XRERR UNIQUE?
J 0
(-3575 2135);
DISPLAY 0.638298 (-3575 2135);
PAINT MONO (-3575 2135);
DISPLAY INVISIBLE (-3575 2135);
WIRE 16 -1 (-2600 2225)(-3425 2225);
FORCEPROP 2 LAST SIG_NAME SMB_P12V_HSC_TEMP_SCL
J 0
(-3335 2235);
DISPLAY 0.510638 (-3335 2235);
PAINT WHITE (-3335 2235);
FORCEPROP 2 LASTPROP $XRERR UNIQUE?
J 0
(-3575 2235);
DISPLAY 0.638298 (-3575 2235);
PAINT MONO (-3575 2235);
DISPLAY INVISIBLE (-3575 2235);
WIRE 16 -1 (-2400 2025)(-2125 2025);
WIRE 16 -1 (-2125 2025)(-1525 2025);
FORCEPROP 2 LAST SIG_NAME P12V_HSC_TEMP_ALERT_R_N
J 0
(-2085 2035);
DISPLAY 0.510638 (-2085 2035);
PAINT WHITE (-2085 2035);
WIRE 16 -1 (-2125 2500)(-2125 2025);
WIRE 16 -1 (-2400 2125)(-1550 2125);
FORCEPROP 2 LAST SIG_NAME SMB_P12V_HSC_SDA
J 0
(-2010 2135);
DISPLAY 0.510638 (-2010 2135);
PAINT WHITE (-2010 2135);
WIRE 16 -1 (-2400 2225)(-1525 2225);
FORCEPROP 2 LAST SIG_NAME SMB_P12V_HSC_SCL
J 0
(-2010 2260);
DISPLAY 0.510638 (-2010 2260);
PAINT WHITE (-2010 2260);
WIRE 16 -1 (-1400 4000)(-750 4000);
FORCEPROP 2 LAST SIG_NAME P12V_HSC_GATE1
J 0
(-1310 4010);
DISPLAY 0.723404 (-1310 4010);
WIRE 16 -1 (-4550 3650)(-4550 3475);
WIRE 16 -1 (-4300 3475)(-4550 3475);
WIRE 16 -1 (-4550 3475)(-5275 3475);
FORCEPROP 2 LAST SIG_NAME A_HSC_LOW_GATE
J 0
(-5085 3485);
DISPLAY 0.723404 (-5085 3485);
WIRE 16 -1 (-6200 3800)(-5675 3800);
WIRE 16 -1 (-5675 3800)(-5675 3475);
WIRE 16 -1 (-5475 3475)(-5675 3475);
WIRE 16 -1 (-6500 3475)(-5675 3475);
FORCEPROP 2 LAST SIG_NAME HSC_D_OC_R2
J 0
(-6435 3485);
DISPLAY 0.723404 (-6435 3485);
FORCEPROP 2 LASTPROP $XRERR UNIQUE?
J 0
(-6675 3485);
DISPLAY 0.638298 (-6675 3485);
PAINT MONO (-6675 3485);
DISPLAY INVISIBLE (-6675 3485);
WIRE 16 -1 (-7050 3800)(-6400 3800);
WIRE 16 -1 (-7050 3525)(-7050 3800);
WIRE 16 -1 (-7050 3525)(-7000 3525);
WIRE 16 -1 (-7100 3525)(-7050 3525);
WIRE 16 -1 (-7100 3175)(-7100 3525);
WIRE 16 -1 (-7925 3525)(-7100 3525);
FORCEPROP 2 LAST SIG_NAME HSC_OC_VOL
J 0
(-7904 3525);
DISPLAY 0.723404 (-7904 3525);
FORCEPROP 2 LASTPROP $XRERR UNIQUE?
J 0
(-8144 3525);
DISPLAY 0.638298 (-8144 3525);
PAINT MONO (-8144 3525);
DISPLAY INVISIBLE (-8144 3525);
WIRE 16 -1 (-7925 3525)(-7925 3650);
WIRE 16 -1 (-7925 3525)(-7925 3175);
WIRE 16 -1 (-7525 3175)(-7525 3425);
WIRE 16 -1 (-7525 3425)(-7000 3425);
WIRE 16 -1 (-8925 3425)(-7525 3425);
FORCEPROP 2 LAST SIG_NAME OC_P2V5_COMP
J 0
(-7785 3435);
DISPLAY 0.723404 (-7785 3435);
FORCEPROP 2 LASTPROP $XRERR UNIQUE?
J 0
(-8025 3435);
DISPLAY 0.638298 (-8025 3435);
PAINT MONO (-8025 3435);
DISPLAY INVISIBLE (-8025 3435);
WIRE 16 -1 (-8925 3600)(-8925 3425);
WIRE 16 -1 (-8925 3025)(-8925 3425);
WIRE 16 -1 (-8925 3025)(-8875 3025);
WIRE 16 -1 (-7925 3950)(-7925 3850);
WIRE 16 -1 (-8325 3950)(-7925 3950);
FORCEPROP 2 LAST SIG_NAME HSC_CSOUT
J 0
(-8304 3950);
DISPLAY 0.723404 (-8304 3950);
WIRE 16 -1 (-3675 6275)(-3625 6275);
WIRE 16 -1 (-3675 6275)(-3825 6275);
WIRE 16 -1 (-3675 5850)(-3675 6275);
WIRE 16 -1 (-4450 5850)(-3675 5850);
WIRE 16 -1 (-4450 5850)(-4450 6125);
WIRE 16 -1 (-4450 5625)(-4450 5850);
WIRE 16 -1 (-5125 5850)(-4450 5850);
FORCEPROP 2 LAST SIG_NAME A_HSC_LOW_GATE
J 0
(-4310 5885);
DISPLAY 0.680851 (-4310 5885);
WIRE 16 -1 (-5875 5750)(-7300 5750);
FORCEPROP 2 LAST SIG_NAME A_HSC_HIGH
J 0
(-7035 5760);
DISPLAY 0.680851 (-7035 5760);
FORCEPROP 2 LASTPROP $XRERR UNIQUE?
J 0
(-7275 5760);
DISPLAY 0.638298 (-7275 5760);
PAINT MONO (-7275 5760);
DISPLAY INVISIBLE (-7275 5760);
WIRE 16 -1 (-7300 6125)(-7300 5750);
WIRE 16 -1 (-7300 5750)(-7300 5525);
WIRE 16 -1 (-5875 5850)(-7775 5850);
FORCEPROP 2 LAST SIG_NAME A_HSC_LOW
J 0
(-7035 5860);
DISPLAY 0.680851 (-7035 5860);
FORCEPROP 2 LASTPROP $XRERR UNIQUE?
J 0
(-7275 5860);
DISPLAY 0.638298 (-7275 5860);
PAINT MONO (-7275 5860);
DISPLAY INVISIBLE (-7275 5860);
WIRE 16 -1 (-7775 6100)(-7775 5850);
WIRE 16 -1 (-7775 5850)(-7775 5575);
WIRE 16 -1 (-6000 6450)(-6375 6450);
WIRE 16 -1 (-6000 6450)(-6000 5900);
WIRE 16 -1 (-6375 6525)(-6375 6450);
WIRE 16 -1 (-6375 6450)(-6375 6350);
WIRE 16 -1 (-6375 6450)(-6825 6450);
FORCEPROP 2 LAST SIG_NAME U142_VS
J 0
(-6760 6460);
DISPLAY 0.680851 (-6760 6460);
FORCEPROP 2 LASTPROP $XRERR UNIQUE?
J 0
(-7000 6460);
DISPLAY 0.638298 (-7000 6460);
PAINT MONO (-7000 6460);
DISPLAY INVISIBLE (-7000 6460);
WIRE 16 -1 (-6825 6450)(-6825 6375);
WIRE 16 -1 (-6000 5900)(-5875 5900);
WIRE 16 -1 (-7950 4925)(-5375 4925);
WIRE 16 -1 (-7950 6500)(-7950 4925);
WIRE 16 -1 (-7775 6500)(-7950 6500);
WIRE 16 -1 (-7950 6500)(-8475 6500);
FORCEPROP 2 LAST SIG_NAME HSC_CSOUT
J 0
(-8285 6510);
DISPLAY 0.680851 (-8285 6510);
WIRE 16 -1 (-7300 6500)(-7775 6500);
WIRE 16 -1 (-7775 6300)(-7775 6500);
WIRE 16 -1 (-7300 6325)(-7300 6500);
WIRE 16 -1 (-1400 4150)(-750 4150);
FORCEPROP 2 LAST SIG_NAME P12V_HSC_SENSE2_N
J 0
(-1310 4160);
DISPLAY 0.723404 (-1310 4160);
WIRE 16 -1 (-1400 3950)(-750 3950);
FORCEPROP 2 LAST SIG_NAME P12V_HSC_GATE2
J 0
(-1310 3960);
DISPLAY 0.723404 (-1310 3960);
WIRE 72 273 (-2950 1075)(-925 1075);
WIRE 72 273 (-2950 775)(-2950 1075);
WIRE 72 273 (-925 775)(-925 1075);
WIRE 72 273 (-2950 775)(-925 775);
WIRE 16 -1 (-2275 1500)(-2275 1250);
WIRE 16 -1 (-2275 1250)(-1950 1250);
WIRE 16 -1 (-3400 1250)(-2275 1250);
FORCEPROP 2 LAST SIG_NAME P12V_HSC_T_CRIT_R_N
J 0
(-3135 1260);
DISPLAY 0.680851 (-3135 1260);
WIRE 16 -1 (-1400 4050)(-750 4050);
FORCEPROP 2 LAST SIG_NAME P12V_HSC_ADC_P
J 0
(-1310 4060);
DISPLAY 0.723404 (-1310 4060);
WIRE 16 -1 (-1400 4100)(-750 4100);
FORCEPROP 2 LAST SIG_NAME P12V_HSC_ADC_N
J 0
(-1310 4110);
DISPLAY 0.723404 (-1310 4110);
WIRE 16 -1 (-1400 4200)(-750 4200);
FORCEPROP 2 LAST SIG_NAME P12V_HSC_SENSE2_P
J 0
(-1310 4210);
DISPLAY 0.723404 (-1310 4210);
WIRE 16 -1 (-1400 4250)(-750 4250);
FORCEPROP 2 LAST SIG_NAME P12V_HSC_SENSE1_N
J 0
(-1310 4260);
DISPLAY 0.723404 (-1310 4260);
WIRE 16 -1 (-1400 4300)(-750 4300);
FORCEPROP 2 LAST SIG_NAME P12V_HSC_SENSE1_P
J 0
(-1310 4310);
DISPLAY 0.723404 (-1310 4310);
WIRE 16 -1 (-1450 2500)(-500 2500);
FORCEPROP 2 LAST SIG_NAME SMB_P12V_HSC_SDA
J 0
(-885 2510);
DISPLAY 0.510638 (-885 2510);
PAINT WHITE (-885 2510);
WIRE 16 -1 (-1450 2725)(-1450 2500);
WIRE 16 -1 (-1325 2600)(-500 2600);
FORCEPROP 2 LAST SIG_NAME SMB_P12V_HSC_SCL
J 0
(-885 2610);
DISPLAY 0.510638 (-885 2610);
PAINT WHITE (-885 2610);
WIRE 16 -1 (-1325 2750)(-1325 2600);
WIRE 16 -1 (-6150 1850)(-6150 1775);
WIRE 16 -1 (-5400 1775)(-6150 1775);
FORCEPROP 2 LAST SIG_NAME P12V_HSC_TEMP_E
J 0
(-6060 1785);
DISPLAY 0.723404 (-6060 1785);
FORCEPROP 2 LASTPROP $XRERR UNIQUE?
J 0
(-6300 1785);
DISPLAY 0.638298 (-6300 1785);
PAINT MONO (-6300 1785);
DISPLAY INVISIBLE (-6300 1785);
WIRE 16 -1 (-2775 6575)(-2775 6325);
WIRE 16 -1 (-3425 6575)(-2775 6575);
FORCEPROP 2 LAST SIG_NAME A_HSC_LOW_DRAIN
J 0
(-3310 6585);
DISPLAY 0.680851 (-3310 6585);
FORCEPROP 2 LASTPROP $XRERR UNIQUE?
J 0
(-3550 6585);
DISPLAY 0.638298 (-3550 6585);
PAINT MONO (-3550 6585);
DISPLAY INVISIBLE (-3550 6585);
WIRE 16 -1 (-3425 6475)(-3425 6575);
WIRE 16 -1 (-6500 4250)(-6500 4200);
WIRE 16 -1 (-6750 4250)(-6500 4250);
WIRE 16 -1 (-6750 3725)(-6750 4250);
WIRE 16 -1 (-6750 4250)(-6750 4275);
WIRE 16 -1 (-7300 5325)(-7300 5250);
WIRE 16 -1 (-7300 5250)(-7775 5250);
WIRE 16 -1 (-7775 5375)(-7775 5250);
WIRE 16 -1 (-7775 5250)(-7775 5050);
WIRE 16 -1 (-1325 3025)(-1325 2950);
WIRE 16 -1 (-1450 3025)(-1325 3025);
WIRE 16 -1 (-1450 2925)(-1450 3025);
WIRE 16 -1 (-1450 3025)(-1450 3050);
WIRE 16 -1 (-1300 3850)(-1400 3850);
WIRE 16 -1 (-1300 3725)(-1300 3850);
WIRE 16 -1 (-6375 6150)(-6375 6050);
WIRE 16 -1 (-6375 6050)(-6825 6050);
WIRE 16 -1 (-6825 6175)(-6825 6050);
WIRE 16 -1 (-6825 6050)(-6825 6025);
DOT 1 (-2300 5750);
DOT 1 (-2150 3750);
DOT 1 (-6750 4250);
DOT 1 (-5675 3475);
DOT 1 (-7100 3525);
DOT 1 (-2275 1250);
DOT 1 (-4575 2725);
DOT 1 (-7775 5850);
DOT 1 (-2225 5750);
DOT 1 (-7950 6500);
DOT 1 (-2775 5750);
DOT 1 (-7300 5750);
DOT 1 (-7775 6500);
DOT 1 (-7775 5250);
DOT 1 (-4450 5850);
DOT 1 (-1450 3025);
DOT 1 (-925 3900);
DOT 1 (-2150 3700);
DOT 1 (-7050 3525);
DOT 1 (-7525 3425);
DOT 1 (-8925 3425);
DOT 1 (-3675 6275);
DOT 1 (-7925 3525);
DOT 1 (-4975 2125);
DOT 1 (-6375 6450);
DOT 1 (-6825 6050);
DOT 1 (-4550 3475);
DOT 1 (-2125 2025);
DOT 1 (-4975 1775);
DOT 1 (-6000 2125);
DOT 1 (-2700 4300);
FORCENOTE
U
(-2900 1000) 0;
DISPLAY LEFT (-2900 1000);
DISPLAY 1.021277 (-2900 1000);
PAINT SKYBLUE (-2900 1000);
FORCENOTE
2ND SOURCE:AL000788001 (G788P81U(MSOP8))
(-2900 850) 0;
DISPLAY LEFT (-2900 850);
DISPLAY 1.021277 (-2900 850);
PAINT SKYBLUE (-2900 850);
FORCENOTE
MAIN SOURCE:AL007718001 (NCT7718W(MSOP))
(-2900 925) 0;
DISPLAY LEFT (-2900 925);
DISPLAY 1.021277 (-2900 925);
PAINT SKYBLUE (-2900 925);
FORCENOTE
PROCHOT
(-5625 5500) 0;
DISPLAY LEFT (-5625 5500);
DISPLAY 1.021277 (-5625 5500);
FORCENOTE
OC DETECT ON MODULE
(-7575 4525) 0;
DISPLAY LEFT (-7575 4525);
DISPLAY 2.510638 (-7575 4525);
PAINT PINK (-7575 4525);
FORCENOTE
ADDRESS: 0X4C (7-BIT) 
(-4200 1550) 0;
DISPLAY LEFT (-4200 1550);
DISPLAY 1.276596 (-4200 1550);
PAINT SKYBLUE (-4200 1550);
FORCENOTE
ADDRESS: 0X98 (8-BIT) 
(-4200 1650) 0;
DISPLAY LEFT (-4200 1650);
DISPLAY 1.276596 (-4200 1650);
PAINT SKYBLUE (-4200 1650);
FORCENOTE
Q6001 CLOSE TO MOSFET
(-6375 2225) 0;
DISPLAY LEFT (-6375 2225);
DISPLAY 1.021277 (-6375 2225);
FORCENOTE
LTC4287=1.5V
(-3525 3650) 0;
DISPLAY LEFT (-3525 3650);
DISPLAY 1.021277 (-3525 3650);
PAINT SKYBLUE (-3525 3650);
FORCENOTE
LTC4282=1.0V
(-3525 3725) 0;
DISPLAY LEFT (-3525 3725);
DISPLAY 1.021277 (-3525 3725);
PAINT SKYBLUE (-3525 3725);
FORCENOTE
$CDS_IMAGE|clipboard_1_19.jpg|1612|241
(-5425 1450) 0;
DISPLAY LEFT (-5425 1450);
QUIT
